G04 ================== begin FILE IDENTIFICATION RECORD ==================*
G04 Layout Name:  DAT6MTH3AD0_t6m_cm_d_brd_103112_274.brd*
G04 Film Name:    pmb*
G04 File Format:  Gerber RS274X*
G04 File Origin:  Cadence Allegro 16.3-S048*
G04 Origin Date:  Tue Nov 26 10:18:25 2013*
G04 *
G04 Layer:  VIA CLASS/PASTEMASK_BOTTOM*
G04 Layer:  PIN/PASTEMASK_BOTTOM*
G04 Layer:  PACKAGE GEOMETRY/PASTEMASK_BOTTOM*
G04 Layer:  MANUFACTURING/PHOTOPLOT_OUTLINE*
G04 Layer:  DRAWING FORMAT/TITLE_BLOCK*
G04 Layer:  DRAWING FORMAT/TITLE_DATA_PMB*
G04 *
G04 Offset:    (0.00 0.00)*
G04 Mirror:    No*
G04 Mode:      Positive*
G04 Rotation:  0*
G04 FullContactRelief:  No*
G04 UndefLineWidth:     6.00*
G04 ================== end FILE IDENTIFICATION RECORD ====================*
%FSLAX25Y25*MOIN*%
%IR0*IPPOS*OFA0.00000B0.00000*MIA0B0*SFA1.00000B1.00000*%
%ADD34R,.004X.02*%
%ADD16O,.04X.135*%
%ADD11R,.006X.012*%
%ADD30C,.03*%
%ADD35R,.016X.005*%
%ADD32R,.0042X.016*%
%AMMACRO31*
21,1,.016,.0042,0.0,0.0,45.*%
%ADD31MACRO31*%
%ADD27R,.016X.0042*%
%ADD50C,.042*%
%ADD13C,.06*%
%ADD46C,.052*%
%ADD45C,.061*%
%ADD10C,.026*%
%ADD15C,.045*%
%ADD42C,.066*%
%ADD21C,.039*%
%ADD53C,.058*%
%ADD49R,.042X.042*%
%ADD48C,.076*%
%ADD12R,.06X.06*%
%ADD47R,.052X.052*%
%ADD44R,.061X.061*%
%ADD23C,.068*%
%ADD14C,.077*%
%ADD17R,.045X.045*%
%ADD40R,.064X.064*%
%ADD43R,.066X.066*%
%ADD54R,.058X.058*%
%ADD22R,.068X.068*%
%ADD18R,.077X.077*%
%ADD51R,.04X.032*%
%ADD41R,.04X.05*%
%ADD26R,.02X.018*%
%ADD36R,.053X.022*%
%ADD20R,.018X.02*%
%ADD52C,.14*%
%ADD37R,.046X.013*%
%ADD39R,.013X.046*%
%ADD29R,.032X.028*%
%ADD28R,.028X.032*%
%ADD25R,.054X.044*%
%ADD38R,.062X.046*%
%ADD24R,.044X.054*%
%ADD33R,.059X.014*%
%ADD19R,.046X.062*%
%ADD55C,.006*%
G75*
%LPD*%
G75*
G54D10*
X-294532Y1044846D03*
X-281332D03*
X-287932D03*
X-267012Y1044916D03*
X20650Y546243D03*
X20350Y555807D03*
X16200Y566921D03*
X11980Y617956D03*
X15349Y614142D03*
X14550Y628297D03*
X13807Y634826D03*
X9300Y631472D03*
X33841Y9183D03*
X36588Y32278D03*
X34008Y91017D03*
X32260Y96899D03*
X33231Y556346D03*
X30672Y551245D03*
X23610Y568111D03*
X34440Y597285D03*
X28112Y591718D03*
X28185Y612088D03*
X30744Y617898D03*
X24168Y655750D03*
X37920Y651828D03*
X49890Y30392D03*
X51580Y17595D03*
X42205Y21518D03*
X54800Y25547D03*
X44010Y55170D03*
X54981Y59420D03*
X54101Y74252D03*
X51340Y69181D03*
X46570Y73891D03*
X47510Y109421D03*
X47420Y433725D03*
X53769Y513033D03*
X54988Y518683D03*
X49857Y520516D03*
X50630Y529281D03*
X50140Y550572D03*
X39540Y538464D03*
X50870Y564008D03*
X43467Y555938D03*
X49680Y579709D03*
X49620Y574212D03*
X47557Y588971D03*
X44507Y594082D03*
X40908Y589691D03*
X39370Y600956D03*
X42950Y612487D03*
X48540Y624953D03*
X52230Y614907D03*
X47480Y616848D03*
X46890Y633564D03*
X53751Y652029D03*
X44640Y651029D03*
X40980Y656396D03*
X56610Y20553D03*
X64190Y72841D03*
X61760Y107321D03*
X55230Y112521D03*
X63900Y112081D03*
X56190Y170026D03*
X57257Y180712D03*
X67853Y180744D03*
X68690Y175589D03*
X66570Y189983D03*
X68830Y215817D03*
X56287Y242872D03*
X63718Y239030D03*
X61945Y267579D03*
X66818Y297483D03*
X57994Y287655D03*
X61357Y477892D03*
X64480Y501596D03*
X62253Y522589D03*
X67369Y522993D03*
X70696Y527237D03*
X67260Y546688D03*
X65900Y566403D03*
X66262Y553344D03*
X65989Y578115D03*
X57710Y572918D03*
X57070Y580074D03*
X69766Y582525D03*
X57440Y585607D03*
X68630Y599945D03*
X61205Y623870D03*
X63570Y613914D03*
X63610Y618917D03*
X61205Y628870D03*
X56240Y630081D03*
X63650Y646957D03*
X61600Y653611D03*
X76030Y156152D03*
X82553Y185431D03*
X82030Y191733D03*
X73870Y205758D03*
X77239Y260814D03*
X81165Y257717D03*
X78373Y276029D03*
X72190Y297395D03*
X77368Y299206D03*
X83084Y389621D03*
X83245Y397913D03*
X85951Y410263D03*
X74291Y486665D03*
X83536Y498308D03*
X81635Y517104D03*
X85346Y512295D03*
X73057Y515286D03*
X72635Y508991D03*
X81491Y533191D03*
X80318Y544311D03*
X75380Y608914D03*
Y603914D03*
X101449Y194368D03*
X101020Y223348D03*
X95951Y376661D03*
X98470Y418834D03*
X91458Y511853D03*
X92422Y531081D03*
X98803Y531597D03*
X97268Y537055D03*
X96200Y616325D03*
X95310Y647481D03*
X97180Y786472D03*
X111220Y160923D03*
X106090Y167615D03*
X112530Y186363D03*
X106760Y175370D03*
X114920Y179082D03*
X108910Y193194D03*
X116960Y394023D03*
X114502Y401262D03*
X107531Y394023D03*
X109972Y509321D03*
X106650Y779581D03*
X102421Y785938D03*
X131068Y76588D03*
X129650Y250414D03*
Y255414D03*
X120144Y401104D03*
X126622Y401436D03*
X132344Y401278D03*
X132902Y394857D03*
X118124Y510811D03*
X124279Y523691D03*
X120300Y572512D03*
X121070Y670509D03*
X132050Y671817D03*
X133607Y686699D03*
X130260Y679836D03*
X132438Y704733D03*
X133490Y695470D03*
X131960Y720941D03*
X119900Y754021D03*
X125600Y759000D03*
X131900Y760900D03*
X125960Y785699D03*
X120090Y780618D03*
X141490Y19267D03*
X137872Y29551D03*
X139931Y40842D03*
X139932Y35310D03*
X135050Y53493D03*
X143857Y51943D03*
X149025Y51720D03*
X135290Y87664D03*
X148330Y258806D03*
X145200Y276468D03*
X138930Y278965D03*
X148350Y281769D03*
X134540Y267786D03*
X145720Y311336D03*
X135224Y323543D03*
X146100D03*
X145580Y316836D03*
X136506Y332193D03*
X139146Y400804D03*
X145284Y401507D03*
X142239Y422346D03*
X135300Y468444D03*
X146240Y472111D03*
X143543Y532024D03*
X141893Y544799D03*
X142087Y538145D03*
X146361Y555387D03*
X149050Y588044D03*
X148200Y669205D03*
X140110Y675907D03*
X139158Y686725D03*
X135280Y679212D03*
X138726Y696707D03*
X138198Y712628D03*
X144631Y735955D03*
X135470Y781697D03*
X145570Y780580D03*
X157877Y30674D03*
X152810Y29921D03*
X158165Y21300D03*
X159861Y36134D03*
X157010Y58963D03*
X164550Y61239D03*
X156440Y74863D03*
X151618Y83343D03*
X164280Y101810D03*
X164490Y127110D03*
X159190Y127781D03*
X152990Y248096D03*
X157690Y249918D03*
X154546Y256986D03*
X152634Y276809D03*
X149721Y292987D03*
X152733Y288517D03*
X158076Y290635D03*
X154581Y308767D03*
X151230Y330164D03*
X150918Y318134D03*
X150510Y336306D03*
X156448Y336629D03*
X162071Y336947D03*
X158605Y364565D03*
X161563Y432521D03*
X154370Y449930D03*
X159690Y465290D03*
X150547Y459363D03*
X162335Y512456D03*
X159196Y515612D03*
X159179Y521893D03*
X154126Y524411D03*
X154475Y530422D03*
X159180Y528227D03*
X162335Y543954D03*
X159185Y537654D03*
X162336Y550253D03*
X164259Y557273D03*
X161280Y581585D03*
X156480Y583315D03*
X150380Y602885D03*
X152442Y627881D03*
X157963Y633735D03*
X161981Y730784D03*
X163138Y778565D03*
X155170Y780656D03*
X160320Y786346D03*
X168961Y27073D03*
X180159Y40661D03*
X165336Y46126D03*
X167383Y93147D03*
X168850Y99251D03*
X169510Y106579D03*
X174710Y105699D03*
X177763Y121057D03*
X168170Y123367D03*
X173170D03*
X178040Y228978D03*
X167483Y239914D03*
X177891Y249324D03*
X175756Y257668D03*
X170501Y259161D03*
X178025Y279018D03*
X178810Y287263D03*
X174148Y289289D03*
X180410Y304866D03*
X172988Y305719D03*
X168110Y350642D03*
X174860Y362416D03*
X180430Y392969D03*
X180440Y398056D03*
X167527Y420268D03*
X179562Y424001D03*
X170683Y436834D03*
X170361Y428595D03*
X169728Y487664D03*
X165970Y497629D03*
X176909Y501153D03*
X168189Y514331D03*
X178085Y512456D03*
X173252Y515693D03*
X165707Y506156D03*
X172087Y510536D03*
X169615Y519216D03*
X178094Y531365D03*
X166297Y532416D03*
X169491Y529702D03*
X166837Y523486D03*
X174395Y527975D03*
X173513Y522854D03*
X168243Y542706D03*
X174930Y547106D03*
X169157Y548676D03*
X173163Y551903D03*
X169444Y558757D03*
X167105Y552882D03*
X178083Y553402D03*
X172889Y562710D03*
X175330Y578535D03*
X166930Y578435D03*
X166786Y569056D03*
X172430Y584035D03*
X177830Y583535D03*
X166570Y583874D03*
X179120Y639615D03*
X169930Y635329D03*
X172510Y639771D03*
X167810Y668131D03*
X171180Y683815D03*
X180820Y717914D03*
X175463Y720245D03*
X174954Y728404D03*
X167568Y743335D03*
X177070Y785736D03*
X177224Y777765D03*
X169860Y782086D03*
X191596Y27620D03*
X184928Y91847D03*
X189928D03*
X196653Y91837D03*
X196493Y105637D03*
X188203Y104567D03*
X194463Y122631D03*
X184050Y230139D03*
X184296Y241098D03*
X181176Y257643D03*
X183440Y269816D03*
X193245Y280285D03*
X189689Y268237D03*
X183198Y278034D03*
X188979Y273444D03*
X191970Y297731D03*
X192298Y286183D03*
X183254Y310663D03*
X183228Y317023D03*
X191159Y317171D03*
X190557Y325701D03*
X195530Y340946D03*
X192040Y333606D03*
X184953Y361563D03*
X182788Y352108D03*
X195420Y372406D03*
X192681Y377554D03*
X193590Y383383D03*
X196273Y403152D03*
X190700Y418325D03*
X182370Y439198D03*
X192527Y429049D03*
X189077Y438281D03*
X192741Y497930D03*
X184843Y533995D03*
X189252Y526236D03*
X191457Y531553D03*
X193466Y546886D03*
X186841Y545372D03*
X194709Y557353D03*
X181491Y557436D03*
X193080Y581235D03*
X182480Y566819D03*
X196740Y589735D03*
X189460Y587915D03*
X192130Y632235D03*
X184748Y639687D03*
X182480Y634585D03*
X191480Y639135D03*
X185993Y682670D03*
X191542Y691925D03*
X181950Y698191D03*
X188566Y722353D03*
X183566D03*
X193566Y722333D03*
X187570Y770605D03*
X192949Y771020D03*
X191081Y785766D03*
X183650Y774332D03*
X182500Y780786D03*
X189770Y778082D03*
X204978Y10605D03*
X204003Y91247D03*
X208908Y96975D03*
X205903Y101477D03*
X210623Y121267D03*
X207154Y175212D03*
X207070Y188978D03*
X205535Y234497D03*
Y228682D03*
X211935Y230585D03*
X205271Y240209D03*
X198685Y237385D03*
Y244085D03*
X210305Y259330D03*
X200977Y256305D03*
X208101Y273007D03*
X197850Y272666D03*
X197468Y289193D03*
X202687Y296024D03*
X198801Y318727D03*
X208000Y325200D03*
X206318Y334987D03*
X200687Y374520D03*
X206973Y361900D03*
X208529Y366783D03*
X201267Y403294D03*
X204584Y462478D03*
X197161Y465628D03*
X203628Y475993D03*
X197628Y489843D03*
X211609Y516553D03*
X205257Y528822D03*
X211287Y528547D03*
X212342Y536729D03*
X199539Y537112D03*
X204309Y539953D03*
X205286Y551130D03*
X211240Y572893D03*
X201510Y576885D03*
X197730Y572893D03*
X197709Y567464D03*
X210790Y566926D03*
X209940Y584893D03*
X198210Y611085D03*
X204024Y604135D03*
Y609135D03*
X208904Y611515D03*
X200380Y629085D03*
X199786Y618893D03*
X202510Y624005D03*
X208904Y616515D03*
X197480Y639815D03*
X203065Y638700D03*
X205221Y630886D03*
X205410Y661200D03*
X211560Y670575D03*
X199590Y682868D03*
X199350Y692724D03*
X196966Y700705D03*
X198566Y722353D03*
X209017Y722344D03*
X203611Y722303D03*
X199760Y763929D03*
X210250Y784919D03*
X202050D03*
X200550Y772046D03*
X206180Y777654D03*
X196886Y779156D03*
X206210Y771577D03*
X212350Y773283D03*
X215773Y90147D03*
X220200Y93561D03*
X226620Y89385D03*
X214320Y101978D03*
X220983Y106174D03*
X213908Y96975D03*
X219510Y101338D03*
X228138Y125802D03*
X226010Y233542D03*
X217135Y230585D03*
Y240785D03*
X216512Y258490D03*
X221784Y256315D03*
X219199Y288344D03*
X214657Y356205D03*
X223831Y359027D03*
X221280Y350255D03*
X214007Y362701D03*
X216687Y374434D03*
X222225Y364031D03*
X227745Y368007D03*
X220687Y370857D03*
X224759Y374125D03*
X214786Y388603D03*
X218090Y390891D03*
X215120Y399654D03*
X214406Y395539D03*
X223085Y401702D03*
X222419Y479933D03*
X218040Y473853D03*
X226255Y472579D03*
X227284Y502591D03*
X213209Y498353D03*
X224209Y491853D03*
X217609Y516353D03*
X219328Y528823D03*
X226909Y528053D03*
X223376Y523322D03*
X225087Y534356D03*
X215946Y544202D03*
X218950Y565589D03*
X227100Y580916D03*
X227838Y566913D03*
X219960Y596373D03*
Y601373D03*
X215699Y625977D03*
X216107Y637977D03*
X228290Y629893D03*
X218240Y674433D03*
X217530Y715305D03*
X221320Y720698D03*
X213310Y719064D03*
X222710Y713706D03*
X216820Y723301D03*
X219520Y770824D03*
X214160Y779627D03*
X226250Y785923D03*
X218270Y785657D03*
X220960Y778561D03*
X226670Y773299D03*
X243373Y88767D03*
X239563Y92077D03*
X233083Y94817D03*
X242913Y106157D03*
X233138Y125802D03*
X232948Y234047D03*
X236710Y244042D03*
X242460Y237591D03*
X237654Y249719D03*
X231710Y240242D03*
X230318Y249425D03*
X228495Y256384D03*
X236618Y270187D03*
X240567Y293811D03*
X240925Y306257D03*
X228432Y321468D03*
X230253Y328616D03*
X232873Y342946D03*
X235220Y348277D03*
X240241Y352958D03*
X228419Y356855D03*
X233635Y357082D03*
X241179Y347675D03*
X230010Y373300D03*
X237578Y369584D03*
X233136Y367070D03*
X243078Y368384D03*
X231257Y362218D03*
X236430Y393470D03*
X231461Y462591D03*
X243471Y460292D03*
X238430Y460338D03*
X228820Y467780D03*
X239700Y486907D03*
X234209Y480953D03*
X228604Y479682D03*
X234909Y489653D03*
X236909Y494453D03*
X236085Y500866D03*
X242502Y496300D03*
X240473Y549168D03*
X242834Y564253D03*
X235307Y566357D03*
X232088Y570503D03*
X241928Y570263D03*
X229269Y597682D03*
X242830Y597415D03*
X234370Y593242D03*
X242796Y589749D03*
X236780Y628738D03*
X229199Y642180D03*
X243693Y632254D03*
X238420Y642148D03*
X229584Y652668D03*
X237451Y652761D03*
X243596Y671772D03*
X229895Y671672D03*
X237275Y679609D03*
X236680Y700668D03*
X242680Y712337D03*
X234960Y714064D03*
X234910Y720816D03*
X238470Y770074D03*
X236180Y786517D03*
X242230Y774803D03*
X231460Y780174D03*
X234011Y772902D03*
X240080Y779908D03*
X258300Y22289D03*
X252683Y105867D03*
X253558Y95038D03*
X256133Y99347D03*
X248558Y95038D03*
X249453Y114307D03*
X244970Y176856D03*
X246003Y197877D03*
X254221Y230582D03*
X256492Y222466D03*
X254418Y240407D03*
X244526Y258705D03*
X256980Y299300D03*
X250469Y305798D03*
X251207Y329651D03*
X251491Y357134D03*
X246410Y348948D03*
X245258Y358468D03*
X258818Y349693D03*
X249410Y368527D03*
X244595Y363535D03*
X256331Y371006D03*
X254445Y364991D03*
X251126Y373722D03*
X254813Y427018D03*
X246465Y464893D03*
X251780Y460883D03*
X257568Y461513D03*
X246509Y486753D03*
X254999Y485763D03*
X250322Y493466D03*
X256809Y496153D03*
X244509Y491353D03*
X254809Y491153D03*
X248609Y498353D03*
X258965Y526457D03*
X255710Y574383D03*
X259678Y581553D03*
X249462Y648383D03*
X257271Y671772D03*
X244780Y682521D03*
X259170Y705138D03*
X258570Y722981D03*
X249190Y769760D03*
X256650Y770638D03*
Y778342D03*
X247900Y778823D03*
X252470Y785797D03*
X244910Y785782D03*
X271421Y7319D03*
X262955Y12663D03*
X266111Y29229D03*
X265789Y20990D03*
X268809Y16400D03*
X274990Y16396D03*
X272245Y89585D03*
X263703Y93847D03*
X262473Y106937D03*
X264980Y121886D03*
X264987Y205682D03*
X260108Y240376D03*
X267118Y245587D03*
X270260Y237037D03*
X273521Y265849D03*
X263774Y256464D03*
X272464Y259964D03*
X261024Y280657D03*
X261463Y296111D03*
X270444Y286183D03*
X268299Y306992D03*
X261915Y302033D03*
X262700Y325494D03*
X263173Y331794D03*
X260970Y343563D03*
X273871Y336662D03*
X269716Y349689D03*
X269886Y358753D03*
X260536Y374216D03*
X270293Y363972D03*
X268118Y374558D03*
X270796Y386643D03*
X263419Y393450D03*
X265162Y401391D03*
X272220Y401343D03*
X274180Y424966D03*
X266822Y443297D03*
X263807Y461234D03*
X260609Y486153D03*
X266205Y483343D03*
X272209Y485753D03*
X273841Y497993D03*
X264909Y498153D03*
X260109Y500153D03*
X263924Y491754D03*
X265009Y515555D03*
X263309Y531253D03*
X266098Y561963D03*
X269609Y576413D03*
X274309Y574653D03*
X261175Y569054D03*
X263792Y574203D03*
X268009Y570953D03*
X273480Y589201D03*
X269428Y622966D03*
X266610Y654171D03*
X261890Y664761D03*
X265550Y668415D03*
X274360Y673831D03*
X267240Y682519D03*
X269420Y677062D03*
X267124Y707892D03*
X273510Y699749D03*
X266170Y694826D03*
X260680Y712988D03*
X271210Y718000D03*
X264600Y723086D03*
X263430Y770417D03*
X275440Y770793D03*
X264340Y778780D03*
X272175Y783074D03*
X266850Y785971D03*
X269890Y773268D03*
X260000Y785233D03*
X284505Y30676D03*
X287766Y21289D03*
X278245Y31043D03*
X276603Y92119D03*
X287423Y91857D03*
X283383Y136155D03*
X284603Y210533D03*
X279161Y237817D03*
X276904Y252550D03*
X282166Y262922D03*
X278811Y259135D03*
X281767Y277742D03*
X290363Y286082D03*
X281818Y290787D03*
X284574Y305700D03*
X276282Y306927D03*
X275832Y329303D03*
X289822Y333092D03*
X281205Y340997D03*
X289191Y341348D03*
X280042Y358589D03*
X275902Y355665D03*
X277040Y376172D03*
X286550Y374402D03*
X281450Y373151D03*
X285390Y390550D03*
X287067Y402358D03*
X276626Y442913D03*
X276347Y459741D03*
X287588Y482033D03*
X284024Y502595D03*
X290323D03*
X281749Y531351D03*
X279658Y574443D03*
X285530Y573002D03*
X283650Y589044D03*
X287997Y649064D03*
X280880Y650295D03*
X278699Y656491D03*
X289365Y673719D03*
X279843Y675688D03*
X282391Y687978D03*
X275710Y681593D03*
X289248Y680521D03*
X286798Y704143D03*
X278370Y705093D03*
X277475Y695723D03*
X285130Y714433D03*
X275880Y722141D03*
X285880Y722268D03*
X280210Y734805D03*
X288390Y734796D03*
X284532Y747493D03*
X275627Y777692D03*
X281930Y773190D03*
X286722Y785929D03*
X278549Y786377D03*
X289028Y778380D03*
X301870Y92072D03*
X296870D03*
X291927Y102991D03*
X296927D03*
X302930Y132994D03*
X299776Y248010D03*
X301511Y262204D03*
X296210Y253187D03*
X292710Y266542D03*
X297810Y280709D03*
X294382Y291966D03*
X291853Y327033D03*
X305880Y339046D03*
X299410Y331201D03*
X300530Y337075D03*
X296218Y353688D03*
X295527Y359812D03*
X293290Y389737D03*
X299533Y394056D03*
X300040Y459733D03*
X298218Y478853D03*
X297370Y498563D03*
X305708Y503043D03*
X304410Y572782D03*
X294909Y578653D03*
X301796Y603917D03*
X298303Y613184D03*
X293843Y642536D03*
X297394Y657033D03*
X302772Y659604D03*
X300880Y664296D03*
X295890Y662662D03*
X295950Y689520D03*
X293068Y677108D03*
X296858Y702544D03*
X297300Y697221D03*
X293300Y718944D03*
X298590Y733669D03*
X293480Y725080D03*
X293440Y748380D03*
X291340Y771217D03*
X295100Y786269D03*
X299249Y771403D03*
X304740Y777277D03*
X297280Y778936D03*
X302440Y784731D03*
X311553Y92347D03*
X310850Y99620D03*
X320740Y98599D03*
X311290Y247249D03*
X315019Y295263D03*
X309347Y291940D03*
X309798Y306104D03*
X311740Y325839D03*
X316670Y316560D03*
X314550Y331564D03*
X318480Y335039D03*
X319288Y350376D03*
X307410Y348380D03*
X313222Y374229D03*
X321297Y367739D03*
X310484Y383312D03*
X317140Y421775D03*
X321910Y410139D03*
X320080Y512736D03*
X320094Y604114D03*
X320512Y613603D03*
X308741Y623871D03*
X311311Y618197D03*
X316183Y644594D03*
X316190Y649621D03*
Y668863D03*
X316184Y662630D03*
Y687630D03*
X316165Y693404D03*
X319620Y716403D03*
X308430Y718693D03*
X321930Y724895D03*
X314930Y724533D03*
X307146Y769416D03*
X315020Y780559D03*
X320657Y779595D03*
X320440Y771967D03*
X311440Y774049D03*
X317020Y786486D03*
X310050Y785923D03*
X335668Y92822D03*
X330668D03*
X325360Y92517D03*
X325970Y98817D03*
X327190Y103818D03*
X337630Y106304D03*
X334720Y102184D03*
X331583Y128717D03*
X331867Y291367D03*
X334622Y302861D03*
X336720Y310846D03*
X337293Y316660D03*
X327058Y358376D03*
X336850Y380332D03*
X331090Y424304D03*
X331900Y419317D03*
X336740Y417069D03*
X322986Y467109D03*
X330115Y490303D03*
X335162Y502791D03*
X326740Y495763D03*
X329672Y502057D03*
X326170Y518386D03*
X335860Y516486D03*
X329348Y533403D03*
X332408Y544097D03*
X336057Y575657D03*
X323931Y589733D03*
X323346Y621930D03*
X337070Y639759D03*
X326350Y638968D03*
X324120Y703114D03*
X332666Y706026D03*
X325560Y713391D03*
X330940Y719125D03*
X338460Y724585D03*
X328280Y770057D03*
X326280Y775980D03*
X337800Y774677D03*
X322871Y785090D03*
X349490Y57698D03*
X352578Y74292D03*
X339750Y73383D03*
X353713Y93057D03*
X344873Y94847D03*
X340450Y101914D03*
X343743Y120967D03*
X351503Y127972D03*
X343220Y280416D03*
X341693Y286010D03*
X342754Y295326D03*
X340792Y307107D03*
X339487Y301038D03*
X351650Y420270D03*
X345270Y452745D03*
X339506Y482841D03*
X348220Y486484D03*
X348870Y501571D03*
X343420Y497966D03*
X340902Y503742D03*
X341512Y512429D03*
X350902Y512520D03*
X346350Y517286D03*
X351964Y599332D03*
X351720Y644191D03*
X348480Y638558D03*
X351730Y649206D03*
Y675057D03*
Y663450D03*
X351720Y670018D03*
X339300Y716800D03*
X342230Y720936D03*
X344710Y785782D03*
X350450Y784982D03*
X338642Y785716D03*
X343370Y779720D03*
X345100Y771906D03*
X350630Y777187D03*
X363025Y12926D03*
X366159Y21822D03*
X361930Y60031D03*
X367300Y60442D03*
X367776Y91746D03*
X358343Y90948D03*
X361470Y101757D03*
X367350Y123927D03*
X356835Y313894D03*
X367220Y303202D03*
X369934Y322946D03*
X364580Y391273D03*
X365850Y414874D03*
X354565Y451562D03*
X354750Y445325D03*
X369507Y464391D03*
X368825Y539776D03*
X361473Y620588D03*
X364950Y639095D03*
X365990Y645272D03*
X367870Y650239D03*
X364980Y655266D03*
X363340Y650512D03*
X365620Y663069D03*
X365380Y668972D03*
X364765Y687963D03*
X365090Y676923D03*
X364115Y692990D03*
X367520Y701710D03*
X357830Y718682D03*
X364750Y727821D03*
X364090Y748565D03*
X357610Y748302D03*
X354870Y771388D03*
X360160Y775523D03*
X363300Y781303D03*
X367904Y778327D03*
X356600Y782086D03*
X362264Y786424D03*
X381907Y21507D03*
X383280Y59940D03*
X376006Y60991D03*
X372776Y91746D03*
X380483Y99047D03*
X378733Y105987D03*
X384863Y95437D03*
X378183Y124904D03*
X372080Y330574D03*
X382190Y388077D03*
X371260Y412879D03*
X371950Y430527D03*
X375190Y463996D03*
X381239Y467171D03*
X371080Y481589D03*
X376540Y498385D03*
X383617Y517862D03*
X376528Y520138D03*
X379733Y549392D03*
X370309Y550322D03*
X382333Y540414D03*
X385573Y629998D03*
X373218Y634217D03*
X382580Y637413D03*
X385145Y652326D03*
X383627Y646254D03*
X379492Y650239D03*
X376089Y646156D03*
X373680Y662417D03*
X376087Y670156D03*
X379461Y675246D03*
X384868Y675433D03*
X379462Y666156D03*
X377673Y686355D03*
X377682Y681355D03*
X377681Y694244D03*
X377679Y701168D03*
X377669Y706237D03*
X372360Y704766D03*
X376770Y734898D03*
X373500Y748457D03*
X370130Y770105D03*
X373370Y783928D03*
X397655Y21336D03*
X397790Y61360D03*
X390355Y75775D03*
X392493Y92647D03*
X400163Y99177D03*
X391310Y99570D03*
X398088Y128455D03*
X393088D03*
X399598Y260251D03*
X398258Y252341D03*
X394378Y260501D03*
X393458Y282931D03*
X392508Y275581D03*
X398038Y292571D03*
X390080Y331575D03*
X395740Y407528D03*
X392076Y470970D03*
X388982Y496939D03*
X396558Y522251D03*
X396470Y527847D03*
X396590Y549310D03*
X399590Y553502D03*
X393596Y567630D03*
X401191Y603637D03*
X391447Y611973D03*
X394389Y604053D03*
X399223Y644930D03*
X394380Y643389D03*
X389856Y645705D03*
X391790Y715248D03*
X400730Y721954D03*
X410713Y76187D03*
X417248Y266301D03*
X404738Y260421D03*
X403148Y270191D03*
X403628Y292201D03*
X406352Y471405D03*
X410607Y485620D03*
X413138Y504813D03*
X407865Y516627D03*
X412088Y521721D03*
X407776Y527426D03*
X405954Y532502D03*
X404336Y545280D03*
X411058Y545353D03*
X408486Y537333D03*
X408736Y551529D03*
X413342Y556219D03*
X412783Y605500D03*
X416454Y621319D03*
X413105Y613739D03*
X403904Y618333D03*
X403970Y642364D03*
X406100Y631851D03*
X413535Y646804D03*
X411982Y660285D03*
X413718Y655267D03*
X415218Y664203D03*
X411675Y672654D03*
X411065Y667516D03*
X416938Y669947D03*
X414183Y686151D03*
X413643Y680004D03*
X414318Y700979D03*
X414080Y721334D03*
X409010Y726147D03*
X415780Y747078D03*
X414130Y779689D03*
X421893Y123537D03*
X421640Y223403D03*
X428405Y245194D03*
X424961Y241203D03*
X418905Y245694D03*
X426992Y250016D03*
X422528Y253531D03*
X426335Y267062D03*
X420858Y261331D03*
X427817Y258829D03*
X421728Y279141D03*
X428748Y275222D03*
X418588Y286681D03*
X421128Y292601D03*
X423178Y284601D03*
X427909Y286759D03*
X427468Y292287D03*
X428747Y463314D03*
Y468770D03*
X422050Y517028D03*
X418660Y541421D03*
X428039Y548119D03*
X421461Y547703D03*
X420883Y556729D03*
X431145Y556608D03*
X429340Y596874D03*
X431520Y607039D03*
X432180Y647458D03*
X425334Y656419D03*
X421080Y665945D03*
X418381Y690878D03*
X427230Y707377D03*
X429240Y721014D03*
X422010Y766690D03*
X421690Y779548D03*
X417880Y786361D03*
X425540Y786506D03*
X431290Y785484D03*
X428250Y772054D03*
X426900Y779752D03*
X417552Y772874D03*
X446920Y78358D03*
X447715Y97926D03*
X444550Y184057D03*
X441580Y250730D03*
X443212Y240957D03*
X441792Y259473D03*
X445890Y283317D03*
X443240Y401984D03*
X437887Y471073D03*
X444920Y485259D03*
X437716Y476295D03*
X445199Y494590D03*
X439749Y506523D03*
X439762Y515540D03*
Y523757D03*
X434605Y521488D03*
X445838Y538085D03*
X441063Y540563D03*
X437832Y556374D03*
X442240Y553337D03*
X435319Y600123D03*
X437120Y612933D03*
X448460Y625960D03*
X437509Y648996D03*
X444700Y651900D03*
X447210Y665143D03*
X447161Y673564D03*
X444458Y669350D03*
X440688Y684438D03*
X442920Y678095D03*
X440688Y689438D03*
X440690Y702386D03*
X440688Y694438D03*
X440660Y712065D03*
X436560Y770904D03*
X444370Y770152D03*
X434540Y778500D03*
X442100Y777623D03*
X446510Y784890D03*
X441006Y785297D03*
X458120Y44721D03*
X464170Y56436D03*
X461594Y99342D03*
X449538Y105144D03*
X453940Y98586D03*
X461880Y150596D03*
X462790Y183489D03*
X450650Y203785D03*
X450576Y234431D03*
X453620Y245162D03*
X451790Y300129D03*
X451504Y529734D03*
X450540Y521331D03*
X463991Y531504D03*
X456722Y529536D03*
X463031Y543563D03*
X453917Y550069D03*
X450367Y540720D03*
X453700Y545047D03*
X453854Y555069D03*
X462270Y612911D03*
X464050Y633877D03*
X458903Y644884D03*
X463178Y647483D03*
X460587Y669424D03*
X457138Y663251D03*
X449060Y721761D03*
X461565Y785806D03*
X463750Y780452D03*
X454120Y785923D03*
X454399Y771873D03*
X457530Y779016D03*
X449610Y777933D03*
X475030Y63879D03*
X470324Y133424D03*
X474813Y162220D03*
X467473Y159766D03*
X473951Y157235D03*
X473950Y172124D03*
X475770Y186451D03*
X471300Y201900D03*
X466200Y207300D03*
X464810Y311253D03*
X480118Y479107D03*
Y474107D03*
X471804Y561085D03*
Y556085D03*
X468740Y585897D03*
X469890Y596580D03*
X476320Y629280D03*
X469229Y638135D03*
X475820Y635422D03*
X468810Y652180D03*
X479512Y649436D03*
X466980Y667059D03*
X479354Y677054D03*
X466070Y774997D03*
X469360Y780411D03*
X475620Y779095D03*
X478290Y786393D03*
X471780Y786300D03*
X486810Y60785D03*
X488438Y109623D03*
X494355Y108674D03*
X490175Y122348D03*
X484350Y112811D03*
X487857Y152147D03*
X492424Y142234D03*
X494467Y148867D03*
X490130Y163086D03*
X493670Y171871D03*
X489040Y169483D03*
X482980Y181071D03*
X488850Y175419D03*
X487839Y194142D03*
X488017Y203716D03*
X486370Y189279D03*
X492700Y223800D03*
X484169Y272867D03*
X486300Y422150D03*
X481300D03*
X482880Y467935D03*
Y462935D03*
X490334Y497342D03*
X483209Y545250D03*
Y550250D03*
X490661Y547148D03*
X489962Y540849D03*
X483838Y566194D03*
Y556148D03*
Y561148D03*
Y571194D03*
X485738Y587125D03*
X490738D03*
X481340Y593296D03*
X494238Y600441D03*
X490600Y608136D03*
X489800Y600200D03*
X487832Y624429D03*
X480310Y642224D03*
X481253Y654837D03*
X484700Y660355D03*
X482398Y673087D03*
X482544Y668042D03*
X490120Y662703D03*
X481227Y685366D03*
Y691366D03*
X490900Y706145D03*
X481227Y696366D03*
X495560Y694781D03*
X488180Y719244D03*
X490890Y714898D03*
X488090Y710545D03*
X488250Y786657D03*
X480770Y778125D03*
X485870Y776087D03*
X491720Y776713D03*
X495110Y771733D03*
X502900Y57670D03*
X500310Y109211D03*
X497430Y124024D03*
X504750Y111749D03*
X509691Y112938D03*
X509710Y127269D03*
X500215Y136449D03*
X502183Y156709D03*
X496360Y167221D03*
X498940Y179744D03*
X510000Y173500D03*
X509100Y191900D03*
X499225Y205296D03*
X506234Y207368D03*
X498867Y227773D03*
X504160Y255584D03*
X497111Y388567D03*
X502111D03*
X505819Y417473D03*
X498238Y417825D03*
X499551Y429636D03*
X502494Y436725D03*
X509486Y433829D03*
X506456Y446928D03*
X502938Y463823D03*
X498119Y470011D03*
X511230Y499059D03*
X506230D03*
X504613Y525200D03*
X503338Y549825D03*
Y544825D03*
X500538Y588525D03*
Y600925D03*
X508400Y617803D03*
X502080Y622999D03*
X505690Y654419D03*
X508061Y645381D03*
X504295Y649612D03*
X504114Y670830D03*
X496453Y670876D03*
X501914Y675624D03*
X504241Y665809D03*
X497320Y665216D03*
X496577Y684553D03*
X505580Y679105D03*
X496277Y678185D03*
X501540Y681970D03*
X506409Y691373D03*
X497350Y699767D03*
X506092Y697575D03*
X501604Y733003D03*
X501890Y746663D03*
X497880Y785893D03*
X509000Y775415D03*
X502480Y782382D03*
X507935Y785704D03*
X511770Y779940D03*
X499270Y776431D03*
X504440Y772548D03*
X513120Y72069D03*
X512878Y108635D03*
X519625Y108543D03*
X526835Y108314D03*
X516146Y113121D03*
X522111Y113310D03*
X518640Y125539D03*
X514510Y133093D03*
X522448Y137674D03*
X523100Y153100D03*
X512600Y147500D03*
X523100Y159400D03*
X515600Y172800D03*
X521320Y178184D03*
X516100Y178100D03*
X526621Y177079D03*
X515231Y191334D03*
X520015Y194584D03*
X523593Y198171D03*
X512200Y196000D03*
X520068Y207142D03*
X516551Y214987D03*
X517670Y247527D03*
X515675Y254098D03*
X525480Y268959D03*
X527438Y340353D03*
X517617Y422944D03*
X514820Y417617D03*
X526440Y422428D03*
X527300Y417368D03*
X517929Y439676D03*
X512867Y443679D03*
X525638Y484023D03*
X524848Y548755D03*
X513998Y568675D03*
X525808Y582665D03*
X514058Y605055D03*
X526300Y623621D03*
X518920Y615387D03*
X514320Y641085D03*
X525692Y654862D03*
X517328Y655529D03*
X521516Y650576D03*
X517222Y673917D03*
X518800Y665776D03*
X515541Y661845D03*
X526430Y664730D03*
X515429Y692278D03*
X526600Y679117D03*
X517888Y687901D03*
X527111Y686052D03*
X515429Y697278D03*
X512548Y722093D03*
X512610Y747115D03*
X519560Y779689D03*
X514430Y785721D03*
X525110Y774395D03*
X519440Y772861D03*
X523683Y786110D03*
X539510Y108742D03*
X536955Y100257D03*
X535960Y112850D03*
X527613Y113373D03*
X538968Y168838D03*
X539500Y196500D03*
X536232Y192086D03*
X529592Y192999D03*
X533474Y196500D03*
X541657Y207645D03*
X532320Y209470D03*
X534208Y227832D03*
X528105Y230594D03*
X535772Y250076D03*
X539267Y267102D03*
X530119Y280101D03*
X533913Y402151D03*
X541650Y422280D03*
X529968Y440216D03*
X529028Y430469D03*
X535352Y440414D03*
X540141Y442994D03*
X537378Y564875D03*
X529408Y603485D03*
X542848Y602975D03*
X535048Y602885D03*
X532420Y615484D03*
X542424Y654821D03*
X536557Y655498D03*
X529525Y669349D03*
X529899Y661020D03*
X539734Y675020D03*
X539577Y721891D03*
X540062Y708779D03*
X531557Y786392D03*
X537320Y786298D03*
X539650Y780942D03*
X529300Y771341D03*
X543075Y775577D03*
X533600Y778780D03*
X527620Y781318D03*
X557995Y110244D03*
X550490Y112989D03*
X552173Y138528D03*
X550599Y132596D03*
X550550Y151682D03*
X558059Y154254D03*
X558348Y142511D03*
X551464Y143862D03*
X550604Y168072D03*
X550370Y157461D03*
X557668Y176534D03*
X551395Y174172D03*
X544500Y197500D03*
X546000Y192000D03*
X557909Y207537D03*
X547148Y220220D03*
X554663Y230782D03*
X545703Y245725D03*
X545981Y236287D03*
X545116Y266847D03*
X547929Y258102D03*
X545223Y276895D03*
X557207Y280328D03*
X555072Y289563D03*
X552090Y388953D03*
X553230Y407251D03*
X549574Y432582D03*
X546384Y445107D03*
X547488Y452373D03*
X554550Y469674D03*
X545513Y469740D03*
X547638Y462356D03*
X546038Y457523D03*
X546250Y490302D03*
X554860Y531701D03*
X549920Y527242D03*
X550149Y604639D03*
X543400Y625963D03*
X552350Y614028D03*
X558281Y637840D03*
X551030Y637200D03*
X543400Y635615D03*
X549314Y647594D03*
X551230Y652844D03*
X551283Y670800D03*
Y699243D03*
X544934Y720820D03*
X550535Y721903D03*
X555551Y722342D03*
X557488Y713709D03*
X553725Y717251D03*
X550004Y709559D03*
X555062Y708679D03*
X545062D03*
X557978Y734053D03*
X545300Y783152D03*
X550940Y771858D03*
X554870Y779438D03*
X549350Y777416D03*
X552830Y785015D03*
X558360Y775757D03*
X569559Y103123D03*
X566105Y112518D03*
X564076Y145372D03*
X563410Y165289D03*
X562195Y159015D03*
X563129Y178369D03*
X569682Y195199D03*
X563775Y227018D03*
X564274Y279395D03*
X561525Y298192D03*
X560865Y285434D03*
X565953Y301635D03*
X565310Y412700D03*
X572440Y464323D03*
Y469323D03*
X562340Y484252D03*
X567791Y528325D03*
X562308Y536895D03*
X566298Y548465D03*
X563188Y541925D03*
X566338Y554235D03*
X561174Y564471D03*
X574738Y579525D03*
X565858Y576195D03*
X561198Y581793D03*
X566378Y567725D03*
X561608Y571775D03*
X574537Y591325D03*
X565398Y584765D03*
X568163Y595115D03*
X561568Y589355D03*
X574071Y606204D03*
X568930Y607754D03*
X574730Y625521D03*
X565647Y637705D03*
X565556Y632431D03*
X571790Y646799D03*
X559440Y650767D03*
X566950Y659439D03*
X571494Y663571D03*
X565168Y664614D03*
Y674614D03*
Y669614D03*
Y684614D03*
Y679614D03*
Y689614D03*
Y694614D03*
Y699614D03*
X560544Y718091D03*
X569604Y721248D03*
X574190Y717805D03*
X564319Y721587D03*
X562540Y713454D03*
X560062Y708679D03*
X570614Y713237D03*
X565062Y708679D03*
X566798Y734023D03*
X569680Y771106D03*
X560150Y781347D03*
X571230Y785131D03*
X562700Y772391D03*
X572720Y777184D03*
X567210Y778530D03*
X563053Y785792D03*
X578938Y103123D03*
X580501Y138336D03*
X583829Y132232D03*
X587968Y138765D03*
X581565Y154969D03*
X579897Y161355D03*
X582792Y167632D03*
X581915Y179955D03*
X588692Y192809D03*
X585580Y210516D03*
X579707Y229395D03*
X585579Y230095D03*
X585874Y281995D03*
X588607Y305034D03*
X576650Y311446D03*
X581650D03*
X585984Y323246D03*
X589070Y423525D03*
X578830Y448192D03*
X585013Y547959D03*
X576208Y542405D03*
X575838Y548935D03*
X577778Y556355D03*
X588780Y611056D03*
X586810Y603344D03*
X588780Y616056D03*
X583930Y652439D03*
X577217Y652002D03*
X576987Y660180D03*
X580637Y663629D03*
X584312Y710716D03*
X583440Y724927D03*
X577570Y734118D03*
X586676Y786016D03*
X583880Y779251D03*
X578330Y785014D03*
X587170Y773768D03*
X579240Y775147D03*
X605070Y123991D03*
X600118Y112568D03*
X592938Y117657D03*
Y140689D03*
Y133232D03*
X594938Y127893D03*
X591707Y230162D03*
X595374Y236795D03*
X594374Y271395D03*
X596574Y276393D03*
X593607Y305034D03*
X590984Y323246D03*
X604338Y338285D03*
X597440Y391690D03*
X590720Y456076D03*
X591100Y450128D03*
X605800Y463167D03*
X603819Y485332D03*
X605798Y501238D03*
X596751Y532108D03*
X603010Y527908D03*
X604820Y555040D03*
X592437Y566543D03*
X601043Y567781D03*
X605396Y590552D03*
X605286Y584152D03*
X593867Y595695D03*
X602314Y607641D03*
Y602641D03*
X593867Y600695D03*
X605430Y622721D03*
X591279Y656223D03*
X596998Y658008D03*
X600736Y668425D03*
X600719Y675156D03*
X597300Y663128D03*
X600690Y691896D03*
X600727Y681876D03*
Y686876D03*
X604220Y703774D03*
X592960Y703291D03*
X601856Y711479D03*
X595950Y708997D03*
X594170Y719290D03*
X603938Y753623D03*
X602424Y778468D03*
X591460Y780096D03*
X596590Y786204D03*
X606270Y774615D03*
X597530Y780191D03*
X592480Y771514D03*
X610543Y107678D03*
X617925Y114064D03*
X613432Y153528D03*
X610415Y237441D03*
X617474Y246495D03*
X617778Y238873D03*
X617274Y257595D03*
X617374Y262695D03*
X613640Y336986D03*
X607671Y344818D03*
X611848Y359784D03*
X607855Y352341D03*
X618581Y354818D03*
X620238Y364369D03*
X609078Y388557D03*
Y393557D03*
X612641Y397478D03*
Y402478D03*
X611050Y423087D03*
X616258Y422211D03*
X610580Y448662D03*
X610010Y456581D03*
X617980Y460408D03*
X621760Y526967D03*
X613470Y537495D03*
X610070Y557588D03*
X610821Y566494D03*
X621937Y567143D03*
X609026Y579132D03*
X617270Y580443D03*
X611520Y596594D03*
X611254Y617943D03*
X615690Y625536D03*
X616730Y633290D03*
X611572Y629894D03*
X613796Y648705D03*
X612950Y656140D03*
X613200Y661577D03*
X620160Y670594D03*
X615940Y666862D03*
X616031Y675149D03*
X612670Y681438D03*
X620180Y678321D03*
X612811Y688422D03*
X607380Y699671D03*
X617930Y703520D03*
X615510Y692781D03*
X620480Y693827D03*
X609070Y721917D03*
X613730Y717663D03*
X620670Y722216D03*
X606940Y716692D03*
X618270Y713344D03*
X619080Y772610D03*
X619030Y778682D03*
X622030Y786047D03*
X606361Y785390D03*
X612260Y783106D03*
X609347Y778624D03*
X628838Y120216D03*
X628738Y133012D03*
X624800Y184953D03*
Y179953D03*
X623301Y200144D03*
Y194544D03*
X634962Y200121D03*
Y195121D03*
X634212Y281670D03*
X624383Y292591D03*
X631672Y301066D03*
X633773Y310439D03*
X628141Y344818D03*
X634511Y389156D03*
X630691Y405007D03*
Y410007D03*
X636586Y410910D03*
X635840Y449890D03*
X634945Y461888D03*
X628250Y471142D03*
X630420Y491511D03*
X636170Y493028D03*
X622600Y488753D03*
X622199Y506535D03*
X632157Y511230D03*
X625130Y534199D03*
X634530Y521565D03*
X634190Y538267D03*
X636890Y571351D03*
X624870Y573143D03*
X627084Y578257D03*
X634921Y580163D03*
X623940Y628720D03*
X636890Y627095D03*
X629781Y628559D03*
X622510Y635544D03*
X634137Y631342D03*
X627146Y638932D03*
X626340Y668853D03*
X633970Y723033D03*
X628160Y722343D03*
X632530Y716788D03*
X636170Y729335D03*
X632300Y749755D03*
X636910Y745815D03*
X624010Y746351D03*
X629912Y769200D03*
X625010Y778281D03*
X639200Y170100D03*
X639350Y250123D03*
X649995Y296433D03*
X640647Y339854D03*
X639838Y349818D03*
X648425Y373474D03*
X652139Y377125D03*
X641236Y381616D03*
X645236Y377858D03*
X650822Y425295D03*
X647280Y446851D03*
X651080Y455238D03*
X652110Y465238D03*
X646600Y463571D03*
X648956Y469323D03*
X650521Y482930D03*
X647921Y475778D03*
X646105Y492010D03*
X650790Y497730D03*
X646906Y505210D03*
X646460Y512967D03*
X652690Y531693D03*
X645040Y524444D03*
X639673Y576888D03*
X651437Y578943D03*
X653301Y585683D03*
X644636Y627257D03*
X646940Y643448D03*
X641263Y631393D03*
X649173Y629876D03*
X647870Y649784D03*
X646580Y654775D03*
X641630Y668783D03*
X647370Y668643D03*
X643740Y716004D03*
X643970Y722649D03*
X645400Y734600D03*
X650160Y733395D03*
X652660Y749000D03*
X640956Y750643D03*
X646680Y755009D03*
X646500Y746300D03*
X638470Y762212D03*
X647410Y767053D03*
X651690Y778099D03*
X640010Y778215D03*
X644110Y773108D03*
X655947Y53677D03*
X655642Y144915D03*
Y149915D03*
X655695Y159567D03*
Y164567D03*
X655030Y228744D03*
Y223744D03*
X657838Y243407D03*
Y238407D03*
X660899Y311515D03*
X654962Y307698D03*
X668925Y364887D03*
X663632Y366698D03*
X669215Y377488D03*
X655812Y424106D03*
X664450Y435739D03*
X664528Y463432D03*
X660458Y470932D03*
X659828Y465162D03*
X667774Y477992D03*
X661158Y486152D03*
X667070Y483608D03*
X662780Y477039D03*
X660518Y492862D03*
X654240Y511568D03*
X653800Y505331D03*
X659933Y513927D03*
X668573Y514155D03*
X659740Y536019D03*
X667050Y535324D03*
X658980Y610043D03*
X663560Y625019D03*
X654221Y631425D03*
X657550Y655072D03*
X669203Y673040D03*
X653870Y668979D03*
X658220Y671797D03*
X659978Y666274D03*
X657340Y690286D03*
X659300Y734119D03*
X657500Y761500D03*
X656970Y772761D03*
X669987Y53672D03*
X679590Y352829D03*
X677083Y375124D03*
X673368Y416621D03*
X671056Y426300D03*
X673740Y449887D03*
X682764Y444832D03*
X677070Y444820D03*
X679299Y491473D03*
X674156Y503662D03*
X677160Y529422D03*
X675044Y524581D03*
X678386Y668420D03*
X673386D03*
X681480Y777388D03*
X681164Y783461D03*
X669810Y786721D03*
X672500Y779579D03*
X687546Y154228D03*
X689480Y194615D03*
X687869Y386780D03*
X688118Y381043D03*
X685859Y403970D03*
X691037Y401739D03*
X696070Y458901D03*
X700590Y462272D03*
X689017Y497282D03*
X694823Y498932D03*
X689729Y509580D03*
X696891Y507279D03*
X686770Y543325D03*
X691532Y563789D03*
Y575789D03*
Y583789D03*
X685640Y634154D03*
X698386Y667241D03*
X693386D03*
X699600Y776000D03*
X689700Y774500D03*
X711676Y51019D03*
X712239Y452293D03*
X704550Y444407D03*
X704766Y498880D03*
X713978Y498075D03*
X716021Y516945D03*
X700829Y504041D03*
X707920Y505575D03*
X706361Y532632D03*
X716260Y525295D03*
X712740Y593101D03*
X713742Y634373D03*
X708386Y669774D03*
X703386D03*
X713445Y677641D03*
X704000Y770800D03*
X731566Y442136D03*
X726580Y455637D03*
X731570Y464043D03*
X726830Y460815D03*
X727940Y469943D03*
X720140Y478333D03*
X719761Y532432D03*
X727830Y641829D03*
X728690Y649829D03*
X718445Y677641D03*
X736310Y450774D03*
X737350Y464330D03*
X734575Y492575D03*
X745500Y492500D03*
X744020Y566143D03*
X743951Y578833D03*
X744050Y571834D03*
X740430Y616409D03*
X744000Y647919D03*
X733210Y645829D03*
X732540Y653829D03*
X758223Y446532D03*
X748723Y455332D03*
X752960Y653967D03*
X771110Y578643D03*
X770850Y587025D03*
G54D20*
X49835Y494618D03*
X52985D03*
X65554Y527977D03*
X62404D03*
X105639Y611918D03*
X102489D03*
X105639Y616418D03*
X102489D03*
X105639Y620918D03*
X102489D03*
X105371Y644345D03*
X102221D03*
X105405Y648617D03*
X102255D03*
X126925Y739100D03*
X130075D03*
Y743200D03*
X126925D03*
X139645Y250914D03*
X142795D03*
X139556Y266048D03*
X142706D03*
X139556Y261548D03*
X142706D03*
X139645Y254914D03*
X142795D03*
X146542Y540950D03*
X146642Y537008D03*
X146634Y550353D03*
Y544853D03*
X147735Y581013D03*
Y573105D03*
Y577105D03*
X147688Y594137D03*
X147753Y610702D03*
X147655Y598135D03*
X147753Y619035D03*
Y614735D03*
X152443Y271487D03*
X155593D03*
X152443Y267487D03*
X155593D03*
X149692Y540950D03*
X149792Y537008D03*
X149784Y550353D03*
Y544853D03*
X152234Y555253D03*
X155384D03*
X150885Y581013D03*
Y573105D03*
Y577105D03*
X150838Y594137D03*
X160538Y596933D03*
X157388D03*
X154755Y588235D03*
X157905D03*
X150903Y610702D03*
X150805Y598135D03*
X160538Y610933D03*
X157388D03*
X160505Y605135D03*
X157355D03*
X160538Y600933D03*
X157388D03*
X150903Y619035D03*
Y614735D03*
X160538Y620933D03*
X157388D03*
X160605Y616735D03*
X157455D03*
X165952Y285347D03*
X169102D03*
X165952Y289347D03*
X169102D03*
X180634Y520053D03*
X178396Y524137D03*
X175954Y539647D03*
X172804D03*
X189998Y112977D03*
X193148D03*
X192205Y311603D03*
X189055D03*
X189182Y305819D03*
X192332D03*
X196372Y313617D03*
X196354Y331014D03*
X184634Y505353D03*
X187784D03*
X185134Y511353D03*
X188284D03*
X183784Y520053D03*
X181546Y524137D03*
X185634Y540853D03*
X188784D03*
X190355Y594735D03*
X193505D03*
X190388Y603833D03*
X193538D03*
X190355Y607835D03*
X193505D03*
X190388Y598933D03*
X193538D03*
X190355Y614735D03*
X193505D03*
X190388Y623033D03*
X193538D03*
X190355Y627135D03*
X193505D03*
X188795Y701936D03*
X191945D03*
X193865Y708156D03*
X210998Y114957D03*
X207848D03*
X205708Y277609D03*
X202558D03*
X211872Y284617D03*
X208022D03*
X204872D03*
X199522Y313617D03*
X209165Y300444D03*
X206015D03*
X206680Y320800D03*
X203530D03*
X199504Y331014D03*
X211423Y521467D03*
X197015Y708156D03*
X224740Y84629D03*
X221590D03*
X226847Y216901D03*
Y220901D03*
X221872Y243617D03*
X225022D03*
X225445Y247519D03*
X222295D03*
Y251519D03*
X225445D03*
X224093Y276987D03*
X220943D03*
X217072Y277567D03*
X213922D03*
X215022Y284617D03*
X218175Y297031D03*
X221325D03*
X218150Y293088D03*
X221300D03*
X216022Y313117D03*
X212872D03*
X216022Y309117D03*
X212872D03*
X219572Y319617D03*
X222722D03*
X219572Y315617D03*
X222722D03*
X227872Y316617D03*
X217134Y502853D03*
X220284D03*
X224193Y498103D03*
X227343D03*
X217134Y506853D03*
X220284D03*
X217134Y510853D03*
X220284D03*
X224529Y511865D03*
X227679D03*
X227784Y515853D03*
X224634D03*
X214573Y521467D03*
X219685Y574231D03*
X222835D03*
X219694Y570116D03*
X222844D03*
X229997Y216901D03*
Y220901D03*
X242064Y242228D03*
Y246228D03*
X231022Y316617D03*
X238022Y324117D03*
X234872D03*
X238022Y320117D03*
X234872D03*
X240913Y377150D03*
X241599Y381197D03*
X242993Y511465D03*
X239843D03*
X243018Y515449D03*
X239868D03*
X243230Y527737D03*
X243240Y519714D03*
X243230Y523732D03*
X243280Y531781D03*
X243266Y535789D03*
X242384Y543962D03*
X243420Y539789D03*
X241348Y703150D03*
X258248Y110597D03*
X255098D03*
X245214Y242228D03*
Y246228D03*
X250837Y246929D03*
X253987D03*
X254022Y251117D03*
X250872D03*
X254022Y255117D03*
X250872D03*
X250943Y277987D03*
X254093D03*
X250516Y294009D03*
X247366D03*
X252943Y284402D03*
X256093D03*
X250454Y299348D03*
X247304D03*
X244063Y377150D03*
X244749Y381197D03*
X246380Y527737D03*
X246390Y519714D03*
X246380Y523732D03*
X246430Y531781D03*
X246416Y535789D03*
X245534Y543962D03*
X246570Y539789D03*
X253293Y546912D03*
X256443D03*
X253273Y542889D03*
X256423D03*
X253239Y561853D03*
X250089D03*
X253239Y566153D03*
X250089D03*
X244498Y703150D03*
X263093Y306987D03*
X259943D03*
X275113Y387669D03*
X271363Y529422D03*
X274513D03*
X271134Y522353D03*
X274284D03*
X271363Y533422D03*
X274513D03*
X260320Y547112D03*
X263470D03*
X260334Y543253D03*
X263484D03*
X271398Y541430D03*
X274548D03*
X271363Y537422D03*
X274513D03*
X280067Y247678D03*
X276917D03*
X288942Y306875D03*
X280494Y330552D03*
X283644D03*
X277821Y349730D03*
X280971D03*
X278263Y387669D03*
X293725Y124910D03*
X296875D03*
X293725Y120910D03*
X296875D03*
X292092Y306875D03*
X300375Y344346D03*
X303525D03*
X306464Y330406D03*
X304970Y334380D03*
X306284Y497853D03*
X303134D03*
X306284Y493853D03*
X303134D03*
X300575Y642208D03*
X303725D03*
Y646192D03*
X300575D03*
X317568Y302798D03*
X314418D03*
X317607Y306876D03*
X314457D03*
X319225Y326386D03*
X316075D03*
X309614Y330406D03*
X308120Y334380D03*
X316331Y378971D03*
X313181D03*
X312675Y639136D03*
X309525D03*
X308785Y651156D03*
X311935D03*
X308785Y659156D03*
X311935D03*
X308785Y655156D03*
X311935D03*
Y647156D03*
X308785D03*
Y675156D03*
X311935D03*
X308785Y663156D03*
X311935D03*
X308785Y671156D03*
X311935D03*
Y667156D03*
X308785D03*
Y683156D03*
X311935D03*
X308785Y687156D03*
X311935D03*
X308785Y691156D03*
X311935D03*
X308785Y679156D03*
X311935D03*
X308785Y699156D03*
X311935D03*
X308785Y695156D03*
X311935D03*
X335798Y117297D03*
X330665Y311864D03*
X327515D03*
X338948Y117297D03*
X351100Y280101D03*
X347950D03*
X351100Y290101D03*
X347950D03*
X351100Y284101D03*
X347950D03*
X351100Y294101D03*
X347950D03*
Y298101D03*
X351100D03*
X344520Y301883D03*
X347670D03*
X351100Y306101D03*
X347950D03*
X350872Y314102D03*
X347722D03*
X347950Y310101D03*
X351100D03*
X351342Y318230D03*
X348192D03*
X361705Y280317D03*
X358555D03*
X361705Y290317D03*
X358555D03*
X361705Y284317D03*
X358555D03*
X361705Y294317D03*
X358555D03*
X361705Y298317D03*
X358555D03*
X359105Y637128D03*
X355955D03*
X359105Y641128D03*
X355955D03*
X359105Y657128D03*
X355955D03*
X359105Y653128D03*
X355955D03*
X359105Y649128D03*
X355955D03*
X359105Y645175D03*
X355955D03*
Y665128D03*
X359105D03*
Y673128D03*
X355955D03*
X359105Y669128D03*
X355955D03*
X359105Y661128D03*
X355955D03*
X359105Y689128D03*
X355955D03*
X359105Y685128D03*
X355955D03*
X359105Y681128D03*
X355955D03*
X359105Y677128D03*
X355955D03*
X359105Y701128D03*
X355955D03*
X359105Y697128D03*
X355955D03*
X359105Y693128D03*
X355955D03*
X357096Y723537D03*
X360246D03*
X369428Y727622D03*
X369336Y735459D03*
X357096Y735537D03*
X360246D03*
X369336Y731459D03*
X357096Y727537D03*
X360246D03*
Y739537D03*
X357096D03*
X369336Y743459D03*
Y739459D03*
X360246Y743537D03*
X357096D03*
X378508Y117817D03*
X375358D03*
X373433Y685656D03*
X370283D03*
Y681656D03*
X373433D03*
Y677656D03*
X370283D03*
X373485Y715026D03*
X376635D03*
X384333Y715248D03*
X372578Y727622D03*
X372486Y735459D03*
Y731459D03*
Y743459D03*
Y739459D03*
X398016Y676213D03*
X394866D03*
X399443Y716254D03*
X387483Y715248D03*
X412631Y264679D03*
X409481D03*
Y260489D03*
X412631D03*
Y256489D03*
X409481D03*
Y252489D03*
X412631D03*
Y272731D03*
X409481D03*
Y268679D03*
X412631D03*
X405343Y676183D03*
X402193D03*
X402593Y716254D03*
X418063Y681569D03*
X421213D03*
X418852Y685654D03*
X422002D03*
X433265Y687156D03*
X436415D03*
Y679156D03*
X433265D03*
Y683156D03*
X436415D03*
X433265Y691156D03*
X436415D03*
X433265Y707156D03*
X436415D03*
X433265Y703156D03*
X436415D03*
X433265Y699156D03*
X436415D03*
X433265Y695156D03*
X436415D03*
X433265Y711156D03*
X436415D03*
X433265Y715156D03*
X436415D03*
X434280Y719128D03*
X437430D03*
X454371Y638786D03*
X451221D03*
X451226Y642685D03*
X454376D03*
X453233Y657403D03*
X450083D03*
X477640Y139364D03*
Y143364D03*
Y147364D03*
Y151364D03*
X479125Y172113D03*
Y164113D03*
Y168113D03*
X478535Y180383D03*
X475385D03*
X479125Y176113D03*
X476385Y556648D03*
X479535D03*
X476385Y560648D03*
X479535D03*
X476385Y566694D03*
X479535D03*
X476385Y570694D03*
X479535D03*
X476366Y656713D03*
X473216D03*
X473363Y663623D03*
X476513D03*
X482126Y126402D03*
X485276D03*
X480790Y139364D03*
X492699Y128666D03*
X480790Y143364D03*
Y147364D03*
Y151364D03*
X482275Y172113D03*
Y164113D03*
Y168113D03*
X494644Y157761D03*
Y162261D03*
X482275Y176113D03*
X493963Y563025D03*
X494063Y567825D03*
Y571725D03*
Y579525D03*
Y575625D03*
X485465Y678656D03*
X488615D03*
X485465Y682656D03*
X488615D03*
Y686656D03*
X485465D03*
X488615Y690656D03*
X485465D03*
X488615Y694656D03*
X485465D03*
X488615Y698656D03*
X485465D03*
X508274Y137686D03*
X505124D03*
X495849Y128666D03*
X508274Y150686D03*
X505124D03*
Y146686D03*
X508274D03*
Y142186D03*
X505124D03*
X497794Y157761D03*
Y162261D03*
X504550Y201800D03*
X507700D03*
X508663Y463223D03*
Y468723D03*
X497113Y563025D03*
X497213Y567825D03*
Y571725D03*
Y579525D03*
Y575625D03*
X509917Y655007D03*
X508578Y666397D03*
X509884Y670488D03*
X511293Y674660D03*
X508143D03*
X509823Y679002D03*
X512465Y120512D03*
X515615D03*
X515438Y137692D03*
X512288D03*
X515401Y153797D03*
X518551D03*
X515458Y142189D03*
X512308D03*
X515375Y159940D03*
X518525D03*
X516875Y182600D03*
X513725D03*
X511813Y463223D03*
Y468723D03*
X521963Y543025D03*
X525113D03*
X512263Y594625D03*
X515413D03*
X524399Y645214D03*
X513067Y655007D03*
X511728Y666397D03*
X513034Y670488D03*
X512973Y679002D03*
X533846Y135146D03*
X530696D03*
X541614Y135415D03*
Y139415D03*
X533846Y139146D03*
X530696D03*
X541614Y151415D03*
X530696Y151146D03*
X533846D03*
X541614Y155415D03*
X530696Y155146D03*
X533846D03*
X541614Y147415D03*
X533846Y143146D03*
X530696D03*
Y147146D03*
X533846D03*
X541614Y143415D03*
X530559Y167329D03*
X533709D03*
X541614Y163415D03*
X530696Y163146D03*
X533846D03*
X541614Y159415D03*
X541675Y216100D03*
X538525D03*
X535763Y452423D03*
X538913D03*
X535363Y470423D03*
X538513D03*
X535763Y460123D03*
X538913D03*
X531527Y483627D03*
X534677D03*
X541622Y644931D03*
X527549Y645214D03*
X541882Y650277D03*
X544764Y135415D03*
Y139415D03*
Y151415D03*
Y155415D03*
Y147415D03*
Y143415D03*
X556699Y149274D03*
X544764Y163415D03*
X551604Y162541D03*
X554754D03*
X544764Y159415D03*
X555863Y183023D03*
X555706Y239501D03*
X552556D03*
X555749Y243395D03*
X552599D03*
X555749Y247595D03*
X552599D03*
X555749Y258095D03*
X552599D03*
X557613Y544225D03*
X554463D03*
X557713Y548125D03*
X554563D03*
X557613Y540325D03*
X554463D03*
X548493Y643163D03*
X551643D03*
X544772Y644931D03*
X545032Y650277D03*
X557765Y669156D03*
Y673156D03*
Y665156D03*
Y677156D03*
Y689156D03*
Y685156D03*
Y681156D03*
Y693156D03*
Y701156D03*
Y697156D03*
X572083Y136404D03*
X568933D03*
X572083Y140404D03*
X568933D03*
X572083Y144404D03*
X568933D03*
X572083Y148404D03*
X568933D03*
X572083Y152404D03*
X568933D03*
X572083Y156404D03*
X568933D03*
X559849Y149274D03*
X568933Y160404D03*
X572083D03*
X559013Y183023D03*
X559333Y643123D03*
X562483D03*
X560915Y669156D03*
Y673156D03*
Y665156D03*
Y677156D03*
Y689156D03*
Y685156D03*
Y681156D03*
Y693156D03*
Y701156D03*
Y697156D03*
X586999Y240895D03*
X590149D03*
X578366Y278093D03*
X581516D03*
Y282093D03*
X578366D03*
Y286093D03*
X581516D03*
X578366Y290093D03*
X581516D03*
Y294093D03*
X578366D03*
X587420Y663828D03*
X590570D03*
X604965Y675156D03*
Y679156D03*
Y683156D03*
Y687156D03*
Y691156D03*
Y695156D03*
X619012Y589645D03*
X615862D03*
X619045Y585543D03*
X615895D03*
X619045Y597943D03*
X615895D03*
X619012Y608845D03*
X615862D03*
X619045Y617943D03*
X615895D03*
X619012Y613745D03*
X615862D03*
X608115Y675156D03*
Y679156D03*
Y683156D03*
Y687156D03*
Y691156D03*
X613086Y697395D03*
X616236D03*
X608115Y695156D03*
X630716Y195307D03*
X627566D03*
X630716Y199307D03*
X627566D03*
X640663Y387285D03*
X643813D03*
X640663Y392085D03*
X643813D03*
X640663Y396985D03*
X643813D03*
Y401583D03*
X640663D03*
Y405883D03*
X643813D03*
X648862Y591745D03*
X652012D03*
X648795Y595943D03*
X651945D03*
X648862Y611745D03*
X652012D03*
X648895Y607543D03*
X652045D03*
X648862Y601745D03*
X652012D03*
X651495Y624443D03*
X648862Y615745D03*
X652012D03*
X651227Y720674D03*
X648077D03*
Y716674D03*
X651227D03*
X649027Y728674D03*
X652177D03*
X648077Y724674D03*
X651227D03*
X661545Y596443D03*
X658395D03*
X661545Y592143D03*
X658395D03*
X661647Y601976D03*
X658497D03*
X664307Y609468D03*
X667457D03*
X661712Y618541D03*
X658562D03*
X654645Y624443D03*
X661745Y614543D03*
X658595D03*
X660889Y676595D03*
X664039D03*
X672363Y388185D03*
X675513D03*
Y392385D03*
X672363D03*
X675513Y401785D03*
X672363D03*
Y406785D03*
X675513D03*
Y397585D03*
X672363D03*
G54D11*
X-36758Y240533D03*
X-34986D03*
G54D12*
X10859Y109561D03*
X73740Y20708D03*
X703661D03*
G54D21*
X71970Y357848D03*
X147590Y647878D03*
X487770Y513674D03*
X577880Y395242D03*
X693400Y758198D03*
X745580Y62870D03*
G54D30*
X160181Y639044D03*
X165803Y643805D03*
X274538Y562523D03*
X284168Y547993D03*
X296338Y548763D03*
X300848Y556253D03*
X399606Y377165D03*
X413386Y363385D03*
X403543Y367322D03*
Y387008D03*
X413386Y390945D03*
X427166Y377165D03*
X423229Y367322D03*
Y387008D03*
X631522Y782841D03*
X635662Y772045D03*
X643417Y568945D03*
X651262Y783605D03*
X654141Y571687D03*
X657482Y782805D03*
G54D22*
X76880Y143269D03*
X739968Y29361D03*
G54D40*
X507489Y281538D03*
G54D13*
X20859Y109561D03*
X83740Y20708D03*
X78740Y30708D03*
X507489Y360278D03*
X713661Y20708D03*
X708661Y30708D03*
G54D31*
X193856Y252341D03*
G54D41*
X502390Y628829D03*
X506390Y637629D03*
X498390D03*
X520782Y629598D03*
X524782Y638398D03*
X528782Y629598D03*
X619202Y651970D03*
X636938Y653637D03*
X623202Y660770D03*
X627202Y651970D03*
X632938Y662437D03*
X640938D03*
G54D14*
X23628Y321764D03*
Y338300D03*
X45282Y321764D03*
G54D23*
X86880Y143269D03*
X749968Y29361D03*
G54D50*
X605796Y189845D03*
Y204845D03*
X611702Y185690D03*
Y178997D03*
Y200690D03*
Y193997D03*
G54D32*
X197073Y265022D03*
G54D33*
X205940Y690317D03*
Y687758D03*
Y685199D03*
Y682640D03*
Y680081D03*
Y705672D03*
Y703113D03*
Y700554D03*
Y697995D03*
Y695436D03*
Y692876D03*
Y708231D03*
X228940Y680081D03*
Y682640D03*
Y685199D03*
Y687758D03*
Y690317D03*
Y692876D03*
Y695436D03*
Y697995D03*
Y700554D03*
Y703113D03*
Y705672D03*
Y708231D03*
X322468Y644505D03*
Y659860D03*
Y657301D03*
Y654742D03*
Y652182D03*
Y649623D03*
Y647064D03*
Y662419D03*
X322440Y673699D03*
Y671140D03*
Y668581D03*
Y691613D03*
Y689054D03*
Y686495D03*
Y683936D03*
Y681376D03*
Y678817D03*
Y676258D03*
Y696731D03*
Y694172D03*
X345468Y644505D03*
Y647064D03*
Y649623D03*
Y652182D03*
Y654742D03*
Y657301D03*
Y659860D03*
Y662419D03*
X345440Y668581D03*
Y671140D03*
Y673699D03*
Y676258D03*
Y678817D03*
Y681376D03*
Y683936D03*
Y686495D03*
Y689054D03*
Y691613D03*
Y694172D03*
Y696731D03*
X383940Y691317D03*
Y688758D03*
Y686199D03*
Y683640D03*
Y681081D03*
Y706672D03*
Y704113D03*
Y701554D03*
Y698995D03*
Y696436D03*
Y693876D03*
Y709231D03*
X406940Y681081D03*
Y683640D03*
Y686199D03*
Y688758D03*
Y691317D03*
Y693876D03*
Y696436D03*
Y698995D03*
Y701554D03*
Y704113D03*
Y706672D03*
Y709231D03*
X446940Y691258D03*
Y688699D03*
Y686140D03*
Y683581D03*
Y706613D03*
Y704054D03*
Y701495D03*
Y698936D03*
Y696376D03*
Y693817D03*
Y711731D03*
Y709172D03*
X469940Y683581D03*
Y686140D03*
Y688699D03*
Y691258D03*
Y693817D03*
Y696376D03*
Y698936D03*
Y701495D03*
Y704054D03*
Y706613D03*
Y709172D03*
Y711731D03*
X571440Y674199D03*
Y671640D03*
Y669081D03*
Y689554D03*
Y686995D03*
Y684436D03*
Y681876D03*
Y679317D03*
Y676758D03*
Y697231D03*
Y694672D03*
Y692113D03*
X594440Y669081D03*
Y671640D03*
Y674199D03*
Y676758D03*
Y679317D03*
Y681876D03*
Y684436D03*
Y686995D03*
Y689554D03*
Y692113D03*
Y694672D03*
Y697231D03*
X627463Y675600D03*
Y690954D03*
Y688395D03*
Y685836D03*
Y683277D03*
Y680718D03*
Y678159D03*
Y706309D03*
Y703750D03*
Y701191D03*
Y698632D03*
Y696073D03*
Y693514D03*
Y708868D03*
X650463Y675600D03*
Y678159D03*
Y680718D03*
Y683277D03*
Y685836D03*
Y688395D03*
Y690954D03*
Y693514D03*
Y696073D03*
Y698632D03*
Y701191D03*
Y703750D03*
Y706309D03*
Y708868D03*
G54D24*
X97627Y426943D03*
X90147D03*
X97627Y435943D03*
X90147D03*
X97627Y444943D03*
X90147D03*
X113858Y453636D03*
X106378D03*
X202207Y222117D03*
X209687D03*
X351910Y331176D03*
X344430D03*
X417881Y412830D03*
X410401D03*
X417881Y420830D03*
X410401D03*
X417881Y428830D03*
X410401D03*
X417881Y436830D03*
X410401D03*
X410551Y452830D03*
X403071D03*
X417881Y444830D03*
X410401D03*
X410551Y460574D03*
X403071D03*
X447841Y424629D03*
Y432798D03*
X455321Y424629D03*
Y432798D03*
X478955Y132391D03*
X486435D03*
G54D51*
X638148Y419286D03*
Y426372D03*
G54D42*
X514780Y28803D03*
X524780D03*
X514780Y38803D03*
X524780D03*
X534780Y28803D03*
X544780D03*
X534780Y38803D03*
X544780D03*
X554780Y28803D03*
X577371D03*
X587371D03*
X577371Y38803D03*
X587371D03*
X597371Y28803D03*
X607371D03*
X597371Y38803D03*
X607371D03*
X617371Y28803D03*
X639963D03*
Y38803D03*
X649963Y28803D03*
Y38803D03*
X659963Y28803D03*
X669963D03*
X659963Y38803D03*
X669963D03*
X679963Y28803D03*
G54D15*
X36024Y187233D03*
Y181225D03*
Y205257D03*
Y199249D03*
Y193241D03*
Y217272D03*
Y211264D03*
X41930Y178221D03*
Y202253D03*
Y196245D03*
Y190237D03*
Y220276D03*
Y214268D03*
Y208260D03*
G54D25*
X118755Y409613D03*
Y417093D03*
X132760Y409149D03*
Y416629D03*
X132135Y497682D03*
Y505162D03*
X140603Y408965D03*
Y416445D03*
X184390Y573395D03*
Y580875D03*
X304851Y323383D03*
Y315903D03*
X501641Y485334D03*
Y492814D03*
X534805Y417861D03*
Y410381D03*
G54D52*
X711575Y143555D03*
Y195355D03*
Y222361D03*
Y274161D03*
X733975Y143555D03*
Y195355D03*
Y222361D03*
Y274161D03*
G54D43*
X554780Y38803D03*
X617371D03*
X679963D03*
G54D16*
X40749Y150808D03*
Y249194D03*
G54D34*
X228130Y225834D03*
X236593Y258887D03*
X244122Y250972D03*
G54D26*
X144058Y370080D03*
Y373230D03*
X148058D03*
Y370080D03*
X147999Y380582D03*
Y383732D03*
X146675Y413599D03*
Y410449D03*
X145531Y526980D03*
Y523830D03*
X152058Y370080D03*
Y373230D03*
X160058Y370080D03*
Y373230D03*
X156058D03*
Y370080D03*
X164058Y373230D03*
Y370080D03*
X156104Y380583D03*
Y383733D03*
X163735Y380294D03*
Y383444D03*
X150709Y506778D03*
Y509928D03*
X149482Y526928D03*
Y523778D03*
X163330Y593010D03*
Y589860D03*
X164163Y625058D03*
Y628208D03*
X179627Y236399D03*
Y239549D03*
X175627Y236399D03*
Y239549D03*
X176058Y370080D03*
Y373230D03*
X168058Y370080D03*
Y373230D03*
X180058D03*
Y370080D03*
X172058Y373230D03*
Y370080D03*
X179801Y380622D03*
Y383772D03*
X171934Y380727D03*
Y383877D03*
X169330Y593010D03*
Y589860D03*
X176263Y593108D03*
Y589958D03*
X176830Y625060D03*
Y628210D03*
X172530Y625060D03*
Y628210D03*
X168430Y624960D03*
Y628110D03*
X179693Y726467D03*
Y729617D03*
X190058Y349894D03*
Y346744D03*
X194185Y349984D03*
Y346834D03*
X184058Y370080D03*
Y373230D03*
X188058D03*
Y370080D03*
X187970Y380726D03*
Y383876D03*
X188886Y553920D03*
Y550770D03*
X183330Y593210D03*
Y590060D03*
X182430Y625260D03*
Y628410D03*
X189940Y714931D03*
Y718081D03*
X185440Y714931D03*
Y718081D03*
X194440Y714898D03*
Y718048D03*
Y739081D03*
Y727581D03*
Y730731D03*
X185440Y727581D03*
Y730731D03*
X189940Y727581D03*
Y730731D03*
Y739081D03*
X185440D03*
X194440Y742231D03*
X189940D03*
X185440D03*
X198653Y281646D03*
X209447Y296692D03*
Y293542D03*
X197847Y297731D03*
X198653Y284796D03*
X209018Y304542D03*
Y307692D03*
X203447Y304742D03*
Y307892D03*
X199447Y304742D03*
Y307892D03*
X197847Y300881D03*
X203520Y327969D03*
Y324819D03*
X196887Y326622D03*
Y323472D03*
X208687Y382271D03*
Y379121D03*
X200687D03*
Y382271D03*
X204687D03*
Y379121D03*
X208209Y486428D03*
Y483278D03*
X207940Y714931D03*
Y718081D03*
X203440Y714898D03*
Y718048D03*
X198940Y714931D03*
Y718081D03*
X207940Y739081D03*
X203440D03*
X198940D03*
X207940Y727581D03*
Y730731D03*
X203440Y727581D03*
Y730731D03*
X198940Y727581D03*
Y730731D03*
X207940Y742231D03*
X203440D03*
X198940D03*
X221421Y233971D03*
Y237121D03*
X217564Y246804D03*
Y249954D03*
X213265Y268130D03*
Y271280D03*
X226995Y269007D03*
Y272157D03*
X222018Y280912D03*
Y284062D03*
X215518Y302042D03*
Y305192D03*
X227947Y309542D03*
Y312692D03*
X227712Y302770D03*
Y299620D03*
X212447Y327042D03*
X220447Y323542D03*
Y326692D03*
X212447Y330192D03*
X227767Y336322D03*
Y333172D03*
X220687Y382271D03*
Y379121D03*
X216687Y382271D03*
Y379121D03*
X212687D03*
Y382271D03*
X224687D03*
Y379121D03*
X212709Y486428D03*
Y483278D03*
X216709Y486428D03*
Y483278D03*
X218867Y521088D03*
Y524238D03*
X225940Y727581D03*
Y730731D03*
X212440Y739081D03*
X221440D03*
X216940Y730731D03*
Y727581D03*
X225940Y739081D03*
X216940D03*
X212440Y730731D03*
Y727581D03*
X221440Y730731D03*
Y727581D03*
X212440Y742231D03*
X221440D03*
X225940D03*
X216940D03*
X228745Y265718D03*
Y262568D03*
X237910Y277692D03*
Y274542D03*
X241525Y278042D03*
Y281192D03*
X234060Y274542D03*
Y277692D03*
X234789Y286926D03*
Y283776D03*
X235107Y297434D03*
X234789Y290675D03*
Y293825D03*
X228408Y291228D03*
Y294378D03*
X228439Y287413D03*
Y284263D03*
X235018Y313042D03*
X240307Y312400D03*
X231600Y303157D03*
Y306307D03*
X235107Y300584D03*
X235018Y316192D03*
X240307Y315550D03*
X235518Y329412D03*
X243612Y336435D03*
Y333285D03*
X235518Y332562D03*
X238643Y360796D03*
Y363946D03*
X236687Y379121D03*
Y382271D03*
X232687Y377621D03*
Y380771D03*
X235319Y470268D03*
Y467118D03*
X241979Y466578D03*
Y469728D03*
X241909Y478128D03*
Y474978D03*
X228689Y494181D03*
Y491031D03*
X240509Y578028D03*
Y574878D03*
X236209Y578028D03*
Y574878D03*
X231809Y578028D03*
Y574878D03*
X239440Y739081D03*
X230440D03*
X234940Y727581D03*
Y730731D03*
X239440D03*
Y727581D03*
X230440Y730731D03*
Y727581D03*
X234940Y739081D03*
X239440Y742231D03*
X230440D03*
X234940D03*
X258263Y245896D03*
Y249046D03*
X252399Y262158D03*
Y265308D03*
X244634Y266202D03*
Y263052D03*
X246947Y278042D03*
Y281192D03*
X248625Y274017D03*
Y270867D03*
X244480Y273876D03*
Y270726D03*
X252261Y272285D03*
Y269135D03*
X256097Y292632D03*
Y289482D03*
X247018Y284912D03*
Y288062D03*
X248250Y310104D03*
Y313254D03*
X252250Y310104D03*
Y313254D03*
X244359Y312651D03*
X256218Y318562D03*
Y315412D03*
X251231Y321857D03*
Y325007D03*
X244359Y315801D03*
X248690Y388933D03*
Y392083D03*
X248687Y379121D03*
Y382271D03*
X252687Y379121D03*
Y382271D03*
X258687Y388902D03*
Y392052D03*
X256687Y379121D03*
Y382271D03*
X251309Y466078D03*
Y469228D03*
X255509Y465978D03*
Y469128D03*
X251309Y478128D03*
Y474978D03*
X255509Y478128D03*
Y474978D03*
X246089Y478179D03*
Y475029D03*
X255048Y516344D03*
X250209Y516778D03*
X259000Y516356D03*
X258748Y509415D03*
Y512565D03*
X255048Y519494D03*
X250209Y519928D03*
X259000Y519506D03*
X249368Y543928D03*
Y547078D03*
X251809Y555928D03*
Y552778D03*
X246209Y553728D03*
Y550578D03*
X248440Y739081D03*
X243940Y727581D03*
Y730731D03*
X257440Y739081D03*
X252940D03*
X257440Y730731D03*
Y727581D03*
X243940Y739081D03*
X252940Y730731D03*
Y727581D03*
X248440Y730731D03*
Y727581D03*
Y742231D03*
X257440D03*
X252940D03*
X243940D03*
X271339Y84895D03*
Y81745D03*
X269625Y100289D03*
Y103439D03*
X264953Y114152D03*
Y117302D03*
X272953Y114152D03*
Y117302D03*
X268953Y114152D03*
Y117302D03*
X262132Y245889D03*
Y249039D03*
X260143Y275621D03*
Y272471D03*
X272218Y318562D03*
Y315412D03*
X264218Y318562D03*
Y315412D03*
X260218Y318562D03*
Y315412D03*
X268218Y318562D03*
Y315412D03*
X260350Y366987D03*
Y363837D03*
X272687Y379121D03*
Y382271D03*
X268687D03*
Y379121D03*
X260687Y382271D03*
Y379121D03*
X260609Y465978D03*
Y469128D03*
X264909Y465978D03*
Y469128D03*
X269209Y465978D03*
Y469128D03*
X273509Y465978D03*
Y469128D03*
X260609Y478128D03*
Y474978D03*
X269109Y478128D03*
Y474978D03*
X264909Y478128D03*
Y474978D03*
X273209Y478128D03*
Y474978D03*
X270209Y490278D03*
Y493428D03*
X274209Y490278D03*
Y493428D03*
X270209Y518428D03*
Y515278D03*
X274209Y518428D03*
Y515278D03*
X267242Y543505D03*
Y546655D03*
X270940Y730731D03*
Y727581D03*
X261940Y739081D03*
X266440D03*
X261940Y730731D03*
Y727581D03*
X270940Y739081D03*
X266440Y730731D03*
Y727581D03*
X261940Y742231D03*
X266440D03*
X270940D03*
X279552Y84908D03*
Y81758D03*
X287905Y84695D03*
Y81545D03*
X283786Y84695D03*
Y81545D03*
X275542Y84928D03*
Y81778D03*
X284199Y106109D03*
Y109259D03*
X276953Y117302D03*
Y114152D03*
X276218Y318562D03*
Y315412D03*
X284218Y318562D03*
Y315412D03*
X280218Y318562D03*
Y315412D03*
X288218Y318562D03*
Y315412D03*
X283498Y367402D03*
Y364252D03*
X276825Y367017D03*
Y363867D03*
X282368Y478188D03*
Y475038D03*
X278311Y478202D03*
Y475052D03*
X278209Y517928D03*
Y514778D03*
X288630Y727362D03*
Y730512D03*
X283440Y739081D03*
X275440D03*
X279940Y727281D03*
Y730431D03*
X287440Y739081D03*
X279440D03*
X275440Y730731D03*
Y727581D03*
X283440Y742231D03*
X275440D03*
X287440D03*
X279440D03*
X295862Y84735D03*
Y81585D03*
X291824Y84815D03*
Y81665D03*
X299135Y322650D03*
Y325800D03*
X292218Y318562D03*
Y315412D03*
X296218Y318562D03*
Y315412D03*
X297131Y369021D03*
Y372171D03*
X301131Y369021D03*
Y372171D03*
X305708Y507818D03*
Y510968D03*
X296913Y510981D03*
Y507831D03*
X301457Y507829D03*
Y510979D03*
X294909Y586128D03*
Y582978D03*
X292420Y652392D03*
Y649242D03*
X296453Y649199D03*
Y652349D03*
X299638Y707048D03*
X303538D03*
X299638Y710198D03*
X303538D03*
X299440Y739081D03*
X291440D03*
X292840Y729522D03*
Y732672D03*
X303440Y739081D03*
X301450Y729345D03*
Y726195D03*
X295440Y739081D03*
X305640Y730942D03*
Y727792D03*
X299440Y742231D03*
X291440D03*
X303440D03*
X295440D03*
X310939Y84815D03*
Y81665D03*
X319005Y84635D03*
Y81485D03*
X314926Y84714D03*
Y81564D03*
X313789Y115659D03*
Y118809D03*
X313190Y342353D03*
Y339203D03*
X321987Y536052D03*
Y539202D03*
X311940Y739081D03*
X307940D03*
X313410Y732276D03*
Y729126D03*
X309530Y730942D03*
Y727792D03*
X311940Y742231D03*
X307940D03*
X327005Y84635D03*
Y81485D03*
X323005Y84635D03*
Y81485D03*
X368920Y716909D03*
Y720059D03*
X364920Y716909D03*
Y720059D03*
X383860Y658089D03*
Y661239D03*
X389999Y665278D03*
Y668428D03*
X407506Y653413D03*
Y650263D03*
X413940Y739081D03*
Y730731D03*
Y727581D03*
Y742231D03*
X427079Y522404D03*
Y519254D03*
X420289Y697510D03*
Y700660D03*
X422940Y727581D03*
Y730731D03*
X426940Y739081D03*
X427440Y727581D03*
Y730731D03*
X418440Y739081D03*
X422940D03*
X431440D03*
X418440Y730731D03*
Y727581D03*
X426940Y742231D03*
X418440D03*
X422940D03*
X431440D03*
X435773Y265453D03*
Y262303D03*
X445440Y727581D03*
Y730731D03*
X435940Y739081D03*
X436440Y727581D03*
Y730731D03*
X444940Y739081D03*
X440440D03*
X440940Y730731D03*
Y727581D03*
X435940Y742231D03*
X444940D03*
X440440D03*
X459000Y202925D03*
Y206075D03*
X450957Y486305D03*
Y489455D03*
X458938Y655198D03*
Y652048D03*
X453235Y647580D03*
Y650730D03*
X449183Y647604D03*
Y650754D03*
X462440Y739081D03*
X453940D03*
X454440Y727581D03*
Y730731D03*
X458440D03*
Y727581D03*
X462440Y730731D03*
Y727581D03*
X458440Y739081D03*
X449940Y730731D03*
Y727581D03*
X449440Y739081D03*
X462440Y742231D03*
X453940D03*
X458440D03*
X449440D03*
X469000Y139925D03*
Y143075D03*
X478000Y210075D03*
Y206925D03*
X473898Y649648D03*
Y652798D03*
X466440Y739081D03*
X470440D03*
Y730731D03*
Y727581D03*
X466440Y730731D03*
Y727581D03*
Y742231D03*
X470440D03*
X495738Y543850D03*
Y547000D03*
X502000Y232425D03*
X506000D03*
X510000D03*
X502000Y235575D03*
X506000D03*
X510000D03*
X498563Y460516D03*
Y457366D03*
X501938Y534030D03*
X506938Y539940D03*
Y536790D03*
X510938Y539940D03*
Y536790D03*
X501938Y537180D03*
X496338Y555750D03*
Y558900D03*
X503628Y571790D03*
Y568640D03*
X507528Y571790D03*
Y568640D03*
X505138Y597300D03*
Y594150D03*
X521320Y170525D03*
X525400Y186475D03*
Y183325D03*
X521400Y186475D03*
Y183325D03*
X521320Y173675D03*
X514059Y230075D03*
Y226925D03*
X517577Y450051D03*
Y446901D03*
X522638Y450298D03*
Y447148D03*
X526638Y533350D03*
X518838D03*
X514938D03*
X522738D03*
X526638Y536500D03*
X518838D03*
X514938D03*
X522738D03*
X519638Y597200D03*
Y594050D03*
X523538Y597300D03*
Y594150D03*
X512533Y626791D03*
Y629941D03*
X514940Y726581D03*
Y729731D03*
X519440Y738081D03*
X523940Y726581D03*
Y729731D03*
X519440D03*
Y726581D03*
X514940Y738081D03*
X523940D03*
X519440Y741231D03*
X514940D03*
X523940D03*
X533768Y186419D03*
Y183269D03*
X537928Y186433D03*
Y183283D03*
X529272Y186459D03*
Y183309D03*
X542002Y186426D03*
Y183276D03*
X531238Y450298D03*
Y447148D03*
X528338Y474348D03*
Y477498D03*
X530538Y533350D03*
X541538Y533250D03*
X534438Y533350D03*
X530538Y536500D03*
X541538Y536400D03*
X534438Y536500D03*
X536438Y597200D03*
Y594050D03*
X531438Y597300D03*
Y594150D03*
X527438Y597300D03*
Y594150D03*
X540338Y597200D03*
Y594050D03*
X537440Y738081D03*
X541940D03*
X532940Y726581D03*
Y729731D03*
X528440Y738081D03*
X541940Y729731D03*
Y726581D03*
X532940Y738081D03*
X537440Y729731D03*
Y726581D03*
X528440Y729731D03*
Y726581D03*
X537440Y741231D03*
X541940D03*
X528440D03*
X532940D03*
X546000Y186426D03*
Y183276D03*
X557174Y269020D03*
Y272170D03*
X545438Y533250D03*
Y536400D03*
X548238Y547950D03*
X555138Y561450D03*
Y564600D03*
X548238Y551100D03*
X555138Y568350D03*
Y571500D03*
X544238Y597200D03*
Y594050D03*
X555138Y587400D03*
Y584250D03*
X548138Y597200D03*
Y594050D03*
X555508Y642118D03*
Y645268D03*
X550940Y738081D03*
X546440D03*
X555440Y738381D03*
X546440Y729731D03*
Y726581D03*
X555440Y729731D03*
Y726581D03*
X550940Y729731D03*
Y726581D03*
Y741231D03*
X546440D03*
X555440Y741531D03*
X563474Y234520D03*
X569874D03*
X563474Y237670D03*
X569874D03*
X566774Y269020D03*
Y272170D03*
X570874Y269020D03*
Y272170D03*
X568940Y726581D03*
Y729731D03*
X564440Y738581D03*
X573440D03*
X559940Y726581D03*
Y729731D03*
X568940Y738581D03*
X573440Y729731D03*
Y726581D03*
X564440Y729731D03*
Y726581D03*
X559940Y738581D03*
X564440Y741731D03*
X573440D03*
X568940D03*
X559940D03*
X576074Y234520D03*
Y237670D03*
X583651Y705451D03*
Y702301D03*
X588151Y705451D03*
Y702301D03*
X579151Y705451D03*
Y702301D03*
X577940Y726581D03*
Y729731D03*
X587940Y738081D03*
Y729731D03*
Y726581D03*
X577940Y738581D03*
X587940Y741231D03*
X577940Y741731D03*
X596741Y242818D03*
Y245968D03*
X604741Y242818D03*
Y245968D03*
X600741D03*
Y242818D03*
X596741Y254218D03*
Y257368D03*
X596641Y266268D03*
Y263118D03*
X604741Y254218D03*
Y257368D03*
X600741D03*
Y254218D03*
X604641Y266268D03*
Y263118D03*
X600641D03*
Y266268D03*
X601440Y738081D03*
X605940D03*
X596940D03*
X592440Y726581D03*
Y729731D03*
Y738081D03*
X596940Y729731D03*
Y726581D03*
X601440Y729731D03*
Y726581D03*
X605940Y729731D03*
Y726581D03*
X601440Y741231D03*
X605940D03*
X596940D03*
X592440D03*
X608741Y242818D03*
Y245968D03*
X612841D03*
Y242818D03*
X608741Y254218D03*
Y257368D03*
X608641Y266268D03*
Y263118D03*
X612774Y263120D03*
Y266270D03*
X612841Y257368D03*
Y254218D03*
X609345Y669937D03*
Y666787D03*
X617235Y682716D03*
Y685866D03*
X619440Y738081D03*
X614940D03*
X610440D03*
X619440Y729731D03*
Y726581D03*
X614940Y729731D03*
Y726581D03*
X610440Y729731D03*
Y726581D03*
X619440Y741231D03*
X614940D03*
X610440D03*
X626970Y587418D03*
Y584268D03*
X632570Y587618D03*
Y584468D03*
X636870Y587618D03*
Y584468D03*
X626070Y619468D03*
Y622618D03*
X633137Y619570D03*
Y622720D03*
X623957Y718092D03*
Y714942D03*
X627957Y718092D03*
Y714942D03*
X623940Y726581D03*
Y729731D03*
Y738081D03*
X628440D03*
X636440D03*
X632440D03*
X628440Y729722D03*
Y726572D03*
X623940Y741231D03*
X628440D03*
X636440D03*
X632440D03*
X648838Y414360D03*
Y411210D03*
X645237Y587620D03*
Y584470D03*
X640970Y587718D03*
Y584568D03*
X646070Y619668D03*
Y622818D03*
X640070Y619668D03*
Y622818D03*
X650339Y660418D03*
X645752Y660431D03*
X650339Y663568D03*
X645752Y663581D03*
X648000Y738925D03*
X652660Y739360D03*
Y742510D03*
X648000Y742075D03*
X668422Y373085D03*
Y369935D03*
X659938Y383660D03*
Y380510D03*
X663938D03*
Y383660D03*
X658338Y414360D03*
Y411210D03*
X653538Y411310D03*
Y414460D03*
X663238D03*
Y411310D03*
X667538Y414360D03*
Y411210D03*
X664503Y672129D03*
Y668979D03*
X661034Y683798D03*
Y680648D03*
X656660Y739360D03*
Y742510D03*
X672522Y369935D03*
Y373085D03*
X683468Y625772D03*
Y628922D03*
X687468Y625772D03*
Y628922D03*
X711261Y625723D03*
Y628873D03*
X715761Y625723D03*
Y628873D03*
X709500Y740425D03*
Y743575D03*
X720261Y625723D03*
Y628873D03*
X729500Y734575D03*
Y731425D03*
Y740425D03*
Y743575D03*
G54D17*
X41930Y184229D03*
G54D44*
X546181Y81889D03*
G54D53*
X712975Y155655D03*
Y165455D03*
Y173455D03*
Y183255D03*
Y234461D03*
Y244261D03*
Y252261D03*
Y262061D03*
X723275Y165455D03*
Y173455D03*
Y183255D03*
Y244261D03*
Y252261D03*
Y262061D03*
G54D35*
X264930Y408493D03*
X467880Y569288D03*
G54D36*
X401329Y650598D03*
Y658078D03*
X391683D03*
Y654338D03*
Y650598D03*
G54D18*
X45282Y338300D03*
G54D54*
X723275Y155655D03*
Y234461D03*
G54D45*
X556181Y81889D03*
G54D27*
X160874Y263034D03*
X159894Y269042D03*
X175200Y265676D03*
X167849Y270242D03*
G54D55*
G01X38493Y-241864D02*
Y-246864D01*
G01X37036Y-241864D02*
X39950D01*
G01X44860Y-246864D02*
X42326D01*
Y-241864D01*
X44860D01*
G01X43846Y-244281D02*
X42326D01*
G01X47426Y-241864D02*
Y-246864D01*
X49960D01*
G01X53793Y-247031D02*
X53666Y-246947D01*
Y-246781D01*
X53793Y-246697D01*
X53920Y-246781D01*
Y-246947D01*
X53793Y-247031D01*
G01Y-244781D02*
X53666Y-244697D01*
Y-244531D01*
X53793Y-244447D01*
X53920Y-244531D01*
Y-244697D01*
X53793Y-244781D01*
G01X58576Y-248531D02*
X57943Y-247697D01*
X57626Y-246864D01*
Y-243531D01*
X57943Y-242697D01*
X58576Y-241864D01*
G01X63993D02*
X63486Y-242031D01*
X63106Y-242447D01*
X62853Y-242947D01*
X62663Y-243614D01*
X62600Y-244364D01*
X62663Y-245114D01*
X62853Y-245781D01*
X63106Y-246281D01*
X63486Y-246697D01*
X63993Y-246864D01*
X64500Y-246697D01*
X64880Y-246281D01*
X65133Y-245781D01*
X65323Y-245114D01*
X65386Y-244364D01*
X65323Y-243614D01*
X65133Y-242947D01*
X64880Y-242447D01*
X64500Y-242031D01*
X63993Y-241864D01*
G01X67700Y-245864D02*
X68080Y-246447D01*
X68586Y-246781D01*
X69156Y-246864D01*
X69663Y-246781D01*
X70170Y-246364D01*
X70486Y-245864D01*
X70550Y-245364D01*
X70423Y-244781D01*
X69980Y-244364D01*
X69536Y-244197D01*
X68966D01*
G01X69536D02*
X69916Y-243947D01*
X70233Y-243531D01*
X70360Y-243031D01*
X70233Y-242531D01*
X69916Y-242114D01*
X69346Y-241864D01*
X68776Y-241947D01*
X68206Y-242281D01*
G01X74510Y-248531D02*
X75143Y-247697D01*
X75460Y-246864D01*
Y-243531D01*
X75143Y-242697D01*
X74510Y-241864D01*
G01X77900Y-245864D02*
X78280Y-246447D01*
X78786Y-246781D01*
X79356Y-246864D01*
X79863Y-246781D01*
X80370Y-246364D01*
X80686Y-245864D01*
X80750Y-245364D01*
X80623Y-244781D01*
X80180Y-244364D01*
X79736Y-244197D01*
X79166D01*
G01X79736D02*
X80116Y-243947D01*
X80433Y-243531D01*
X80560Y-243031D01*
X80433Y-242531D01*
X80116Y-242114D01*
X79546Y-241864D01*
X78976Y-241947D01*
X78406Y-242281D01*
G01X83190Y-242697D02*
X83570Y-242197D01*
X84013Y-241947D01*
X84520Y-241864D01*
X85153Y-242031D01*
X85596Y-242447D01*
X85723Y-242947D01*
X85660Y-243447D01*
X85406Y-243864D01*
X84140Y-244697D01*
X83570Y-245281D01*
X83190Y-246114D01*
X83063Y-246864D01*
X85723D01*
G01X89366D02*
X89493Y-245781D01*
X89683Y-244864D01*
X89936Y-244031D01*
X90253Y-243114D01*
X90760Y-241864D01*
X88226D01*
G01X93770Y-245197D02*
X95416D01*
G01X98490Y-242697D02*
X98870Y-242197D01*
X99313Y-241947D01*
X99820Y-241864D01*
X100453Y-242031D01*
X100896Y-242447D01*
X101023Y-242947D01*
X100960Y-243447D01*
X100706Y-243864D01*
X99440Y-244697D01*
X98870Y-245281D01*
X98490Y-246114D01*
X98363Y-246864D01*
X101023D01*
G01X103400Y-245864D02*
X103780Y-246447D01*
X104286Y-246781D01*
X104856Y-246864D01*
X105363Y-246781D01*
X105870Y-246364D01*
X106186Y-245864D01*
X106250Y-245364D01*
X106123Y-244781D01*
X105680Y-244364D01*
X105236Y-244197D01*
X104666D01*
G01X105236D02*
X105616Y-243947D01*
X105933Y-243531D01*
X106060Y-243031D01*
X105933Y-242531D01*
X105616Y-242114D01*
X105046Y-241864D01*
X104476Y-241947D01*
X103906Y-242281D01*
G01X110653Y-246864D02*
Y-241864D01*
X108310Y-245447D01*
X111476D01*
G01X113600Y-246114D02*
X113980Y-246531D01*
X114423Y-246781D01*
X114993Y-246864D01*
X115563Y-246697D01*
X116006Y-246364D01*
X116323Y-245781D01*
X116386Y-245114D01*
X116260Y-244447D01*
X115943Y-244031D01*
X115500Y-243697D01*
X115056Y-243614D01*
X114613Y-243697D01*
X114043Y-244031D01*
X114233Y-241864D01*
X115943D01*
G01X123990Y-246864D02*
Y-241864D01*
X126396D01*
G01X125510Y-244281D02*
X123990D01*
G01X128710Y-246864D02*
X130293Y-241864D01*
X131876Y-246864D01*
G01X131306Y-245114D02*
X129280D01*
G01X134063Y-246864D02*
X136723Y-241864D01*
G01X134063D02*
X136723Y-246864D01*
G01X140493Y-247031D02*
X140366Y-246947D01*
Y-246781D01*
X140493Y-246697D01*
X140620Y-246781D01*
Y-246947D01*
X140493Y-247031D01*
G01Y-244781D02*
X140366Y-244697D01*
Y-244531D01*
X140493Y-244447D01*
X140620Y-244531D01*
Y-244697D01*
X140493Y-244781D01*
G01X145276Y-248531D02*
X144643Y-247697D01*
X144326Y-246864D01*
Y-243531D01*
X144643Y-242697D01*
X145276Y-241864D01*
G01X150693D02*
X150186Y-242031D01*
X149806Y-242447D01*
X149553Y-242947D01*
X149363Y-243614D01*
X149300Y-244364D01*
X149363Y-245114D01*
X149553Y-245781D01*
X149806Y-246281D01*
X150186Y-246697D01*
X150693Y-246864D01*
X151200Y-246697D01*
X151580Y-246281D01*
X151833Y-245781D01*
X152023Y-245114D01*
X152086Y-244364D01*
X152023Y-243614D01*
X151833Y-242947D01*
X151580Y-242447D01*
X151200Y-242031D01*
X150693Y-241864D01*
G01X154400Y-245864D02*
X154780Y-246447D01*
X155286Y-246781D01*
X155856Y-246864D01*
X156363Y-246781D01*
X156870Y-246364D01*
X157186Y-245864D01*
X157250Y-245364D01*
X157123Y-244781D01*
X156680Y-244364D01*
X156236Y-244197D01*
X155666D01*
G01X156236D02*
X156616Y-243947D01*
X156933Y-243531D01*
X157060Y-243031D01*
X156933Y-242531D01*
X156616Y-242114D01*
X156046Y-241864D01*
X155476Y-241947D01*
X154906Y-242281D01*
G01X161210Y-248531D02*
X161843Y-247697D01*
X162160Y-246864D01*
Y-243531D01*
X161843Y-242697D01*
X161210Y-241864D01*
G01X164600Y-245864D02*
X164980Y-246447D01*
X165486Y-246781D01*
X166056Y-246864D01*
X166563Y-246781D01*
X167070Y-246364D01*
X167386Y-245864D01*
X167450Y-245364D01*
X167323Y-244781D01*
X166880Y-244364D01*
X166436Y-244197D01*
X165866D01*
G01X166436D02*
X166816Y-243947D01*
X167133Y-243531D01*
X167260Y-243031D01*
X167133Y-242531D01*
X166816Y-242114D01*
X166246Y-241864D01*
X165676Y-241947D01*
X165106Y-242281D01*
G01X170016Y-246281D02*
X170460Y-246697D01*
X170966Y-246864D01*
X171473Y-246697D01*
X171916Y-246197D01*
X172233Y-245447D01*
X172360Y-244697D01*
Y-243781D01*
X172233Y-243031D01*
X171916Y-242364D01*
X171536Y-242031D01*
X171093Y-241864D01*
X170586Y-242031D01*
X170206Y-242364D01*
X169953Y-242864D01*
X169826Y-243531D01*
X169953Y-244114D01*
X170270Y-244697D01*
X170650Y-245031D01*
X171093Y-245114D01*
X171600Y-244947D01*
X171980Y-244531D01*
X172360Y-243781D01*
G01X176066Y-246864D02*
X176193Y-245781D01*
X176383Y-244864D01*
X176636Y-244031D01*
X176953Y-243114D01*
X177460Y-241864D01*
X174926D01*
G01X180470Y-245197D02*
X182116D01*
G01X185000Y-245864D02*
X185380Y-246447D01*
X185886Y-246781D01*
X186456Y-246864D01*
X186963Y-246781D01*
X187470Y-246364D01*
X187786Y-245864D01*
X187850Y-245364D01*
X187723Y-244781D01*
X187280Y-244364D01*
X186836Y-244197D01*
X186266D01*
G01X186836D02*
X187216Y-243947D01*
X187533Y-243531D01*
X187660Y-243031D01*
X187533Y-242531D01*
X187216Y-242114D01*
X186646Y-241864D01*
X186076Y-241947D01*
X185506Y-242281D01*
G01X190290Y-244781D02*
X190733Y-244197D01*
X191113Y-243864D01*
X191620Y-243697D01*
X192063Y-243864D01*
X192380Y-244197D01*
X192633Y-244697D01*
X192696Y-245281D01*
X192633Y-245781D01*
X192380Y-246281D01*
X192000Y-246697D01*
X191556Y-246864D01*
X191050Y-246697D01*
X190606Y-246197D01*
X190353Y-245447D01*
X190290Y-244614D01*
X190416Y-243531D01*
X190606Y-242947D01*
X190923Y-242364D01*
X191366Y-241947D01*
X191810Y-241864D01*
X192253Y-242031D01*
X192570Y-242447D01*
G01X196593Y-246864D02*
Y-241864D01*
X195833Y-242864D01*
G01Y-246864D02*
X197353D01*
G01X202453D02*
Y-241864D01*
X200110Y-245447D01*
X203276D01*
G01X26493Y-176864D02*
Y-251864D01*
X526493D01*
Y-176864D01*
X26493D01*
G01X221493D02*
Y-251864D01*
G01Y-226864D02*
X324493D01*
Y-201864D01*
G01X221493D02*
X324493D01*
G01X332000Y-236864D02*
Y-231864D01*
X333266D01*
X333773Y-232114D01*
X334153Y-232447D01*
X334470Y-232947D01*
X334723Y-233531D01*
X334786Y-234364D01*
X334723Y-235197D01*
X334470Y-235781D01*
X334153Y-236281D01*
X333773Y-236614D01*
X333266Y-236864D01*
X332000D01*
G01X336910D02*
X338493Y-231864D01*
X340076Y-236864D01*
G01X339506Y-235114D02*
X337480D01*
G01X343593Y-231864D02*
Y-236864D01*
G01X342136Y-231864D02*
X345050D01*
G01X349960Y-236864D02*
X347426D01*
Y-231864D01*
X349960D01*
G01X348946Y-234281D02*
X347426D01*
G01X353793Y-237031D02*
X353666Y-236947D01*
Y-236781D01*
X353793Y-236697D01*
X353920Y-236781D01*
Y-236947D01*
X353793Y-237031D01*
G01Y-234781D02*
X353666Y-234697D01*
Y-234531D01*
X353793Y-234447D01*
X353920Y-234531D01*
Y-234697D01*
X353793Y-234781D01*
G01X326493Y-176864D02*
Y-251864D01*
G01X324493Y-176864D02*
Y-251864D01*
G01X326493Y-226864D02*
X526493D01*
G01X332126Y-211864D02*
Y-206864D01*
X333646D01*
X334153Y-207114D01*
X334533Y-207697D01*
X334660Y-208364D01*
X334533Y-209031D01*
X334216Y-209531D01*
X333646Y-209781D01*
X332126D01*
G01X337353Y-212031D02*
X339633Y-206864D01*
G01X342136Y-211864D02*
Y-206864D01*
X345050Y-211864D01*
Y-206864D01*
G01X348693Y-212031D02*
X348566Y-211947D01*
Y-211781D01*
X348693Y-211697D01*
X348820Y-211781D01*
Y-211947D01*
X348693Y-212031D01*
G01Y-209781D02*
X348566Y-209697D01*
Y-209531D01*
X348693Y-209447D01*
X348820Y-209531D01*
Y-209697D01*
X348693Y-209781D01*
G01X326493Y-201864D02*
X526493D01*
G01X332126Y-186864D02*
Y-181864D01*
X333646D01*
X334153Y-182114D01*
X334533Y-182697D01*
X334660Y-183364D01*
X334533Y-184031D01*
X334216Y-184531D01*
X333646Y-184781D01*
X332126D01*
G01X337226Y-186864D02*
Y-181864D01*
X338810D01*
X339316Y-182114D01*
X339633Y-182447D01*
X339760Y-183114D01*
X339633Y-183781D01*
X339253Y-184197D01*
X338810Y-184447D01*
X337226D01*
G01X338810D02*
X339760Y-186864D01*
G01X343593D02*
X343086Y-186781D01*
X342643Y-186447D01*
X342263Y-185947D01*
X342010Y-185364D01*
X341883Y-184697D01*
Y-184031D01*
X342010Y-183364D01*
X342263Y-182781D01*
X342643Y-182281D01*
X343086Y-181947D01*
X343593Y-181864D01*
X344100Y-181947D01*
X344543Y-182281D01*
X344923Y-182781D01*
X345176Y-183364D01*
X345303Y-184031D01*
Y-184697D01*
X345176Y-185364D01*
X344923Y-185947D01*
X344543Y-186447D01*
X344100Y-186781D01*
X343593Y-186864D01*
G01X347426Y-185864D02*
X347743Y-186364D01*
X348123Y-186697D01*
X348566Y-186864D01*
X349073Y-186697D01*
X349453Y-186364D01*
X349833Y-185864D01*
X349960Y-185197D01*
Y-181864D01*
G01X355060Y-186864D02*
X352526D01*
Y-181864D01*
X355060D01*
G01X354046Y-184281D02*
X352526D01*
G01X360286Y-182281D02*
X359906Y-182031D01*
X359463Y-181864D01*
X358956D01*
X358386Y-182114D01*
X357943Y-182531D01*
X357626Y-183031D01*
X357373Y-183864D01*
X357310Y-184614D01*
X357436Y-185364D01*
X357626Y-185864D01*
X358006Y-186364D01*
X358450Y-186697D01*
X358893Y-186864D01*
X359336D01*
X359780Y-186697D01*
X360160Y-186447D01*
X360476Y-186114D01*
G01X363993Y-181864D02*
Y-186864D01*
G01X362536Y-181864D02*
X365450D01*
G01X369093Y-187031D02*
X368966Y-186947D01*
Y-186781D01*
X369093Y-186697D01*
X369220Y-186781D01*
Y-186947D01*
X369093Y-187031D01*
G01Y-184781D02*
X368966Y-184697D01*
Y-184531D01*
X369093Y-184447D01*
X369220Y-184531D01*
Y-184697D01*
X369093Y-184781D01*
G01X447126Y-236864D02*
Y-231864D01*
X448710D01*
X449216Y-232114D01*
X449533Y-232447D01*
X449660Y-233114D01*
X449533Y-233781D01*
X449153Y-234197D01*
X448710Y-234447D01*
X447126D01*
G01X448710D02*
X449660Y-236864D01*
G01X454760D02*
X452226D01*
Y-231864D01*
X454760D01*
G01X453746Y-234281D02*
X452226D01*
G01X457010Y-231864D02*
X458593Y-236864D01*
X460176Y-231864D01*
G01X463693Y-237031D02*
X463566Y-236947D01*
Y-236781D01*
X463693Y-236697D01*
X463820Y-236781D01*
Y-236947D01*
X463693Y-237031D01*
G01Y-234781D02*
X463566Y-234697D01*
Y-234531D01*
X463693Y-234447D01*
X463820Y-234531D01*
Y-234697D01*
X463693Y-234781D01*
G01X441493Y-226864D02*
Y-251864D01*
G01X490493Y-226864D02*
Y-251864D01*
G01X-1043962Y-705877D02*
Y2342823D01*
X2300638D01*
Y-705877D01*
X-1043962D01*
G01X37198Y-238524D02*
X37825Y-239049D01*
X38530Y-239364D01*
X39156D01*
X39783Y-239049D01*
X40253Y-238524D01*
X40488Y-237789D01*
X40331Y-237054D01*
X39940Y-236424D01*
X39235Y-236004D01*
X38295Y-235794D01*
X37746Y-235374D01*
X37511Y-234639D01*
X37668Y-233904D01*
X38060Y-233379D01*
X38608Y-233064D01*
X39156D01*
X39705Y-233274D01*
X40175Y-233799D01*
G01X43498Y-239364D02*
Y-233064D01*
G01X46788D02*
Y-239364D01*
G01Y-236214D02*
X43498D01*
G01X50503Y-233064D02*
X52383D01*
G01X51443D02*
Y-239364D01*
G01X50503D02*
X52383D01*
G01X59310D02*
X56176D01*
Y-233064D01*
X59310D01*
G01X58056Y-236109D02*
X56176D01*
G01X62241Y-239364D02*
Y-233064D01*
X65845Y-239364D01*
Y-233064D01*
G01X70186Y-240519D02*
X70500Y-239154D01*
G01X76643Y-233064D02*
Y-239364D01*
G01X74841Y-233064D02*
X78445D01*
G01X80985Y-239364D02*
X82943Y-233064D01*
X84901Y-239364D01*
G01X84196Y-237159D02*
X81690D01*
G01X88303Y-233064D02*
X90183D01*
G01X89243D02*
Y-239364D01*
G01X88303D02*
X90183D01*
G01X93193Y-233064D02*
X94290Y-239364D01*
X95543Y-233064D01*
X96796Y-239364D01*
X97893Y-233064D01*
G01X99885Y-239364D02*
X101843Y-233064D01*
X103801Y-239364D01*
G01X103096Y-237159D02*
X100590D01*
G01X106341Y-239364D02*
Y-233064D01*
X109945Y-239364D01*
Y-233064D01*
G01X119176Y-239364D02*
Y-233064D01*
X121135D01*
X121761Y-233379D01*
X122153Y-233799D01*
X122310Y-234639D01*
X122153Y-235479D01*
X121683Y-236004D01*
X121135Y-236319D01*
X119176D01*
G01X121135D02*
X122310Y-239364D01*
G01X127043Y-239574D02*
X126886Y-239469D01*
Y-239259D01*
X127043Y-239154D01*
X127200Y-239259D01*
Y-239469D01*
X127043Y-239574D01*
G01X133343Y-239364D02*
X132716Y-239259D01*
X132168Y-238839D01*
X131698Y-238209D01*
X131385Y-237474D01*
X131228Y-236634D01*
Y-235794D01*
X131385Y-234954D01*
X131698Y-234219D01*
X132168Y-233589D01*
X132716Y-233169D01*
X133343Y-233064D01*
X133970Y-233169D01*
X134518Y-233589D01*
X134988Y-234219D01*
X135301Y-234954D01*
X135458Y-235794D01*
Y-236634D01*
X135301Y-237474D01*
X134988Y-238209D01*
X134518Y-238839D01*
X133970Y-239259D01*
X133343Y-239364D01*
G01X139643Y-239574D02*
X139486Y-239469D01*
Y-239259D01*
X139643Y-239154D01*
X139800Y-239259D01*
Y-239469D01*
X139643Y-239574D01*
G01X147666Y-233589D02*
X147196Y-233274D01*
X146648Y-233064D01*
X146021D01*
X145316Y-233379D01*
X144768Y-233904D01*
X144376Y-234534D01*
X144063Y-235584D01*
X143985Y-236529D01*
X144141Y-237474D01*
X144376Y-238104D01*
X144846Y-238734D01*
X145395Y-239154D01*
X145943Y-239364D01*
X146491D01*
X147040Y-239154D01*
X147510Y-238839D01*
X147901Y-238419D01*
G01X152243Y-239574D02*
X152086Y-239469D01*
Y-239259D01*
X152243Y-239154D01*
X152400Y-239259D01*
Y-239469D01*
X152243Y-239574D01*
G01X37120Y-229364D02*
Y-223064D01*
G01X40096D02*
X37120Y-226949D01*
G01X40566Y-229364D02*
X38451Y-225164D01*
G01X43420Y-223064D02*
Y-227579D01*
X43733Y-228524D01*
X44360Y-229154D01*
X45143Y-229364D01*
X45926Y-229154D01*
X46553Y-228524D01*
X46866Y-227579D01*
Y-223064D01*
G01X53010Y-229364D02*
X49876D01*
Y-223064D01*
X53010D01*
G01X51756Y-226109D02*
X49876D01*
G01X56803Y-223064D02*
X58683D01*
G01X57743D02*
Y-229364D01*
G01X56803D02*
X58683D01*
G01X68698Y-228524D02*
X69325Y-229049D01*
X70030Y-229364D01*
X70656D01*
X71283Y-229049D01*
X71753Y-228524D01*
X71988Y-227789D01*
X71831Y-227054D01*
X71440Y-226424D01*
X70735Y-226004D01*
X69795Y-225794D01*
X69246Y-225374D01*
X69011Y-224639D01*
X69168Y-223904D01*
X69560Y-223379D01*
X70108Y-223064D01*
X70656D01*
X71205Y-223274D01*
X71675Y-223799D01*
G01X74998Y-229364D02*
Y-223064D01*
G01X78288D02*
Y-229364D01*
G01Y-226214D02*
X74998D01*
G01X80985Y-229364D02*
X82943Y-223064D01*
X84901Y-229364D01*
G01X84196Y-227159D02*
X81690D01*
G01X87441Y-229364D02*
Y-223064D01*
X91045Y-229364D01*
Y-223064D01*
G01X100198Y-229364D02*
Y-223064D01*
G01X103488D02*
Y-229364D01*
G01Y-226214D02*
X100198D01*
G01X106498Y-228524D02*
X107125Y-229049D01*
X107830Y-229364D01*
X108456D01*
X109083Y-229049D01*
X109553Y-228524D01*
X109788Y-227789D01*
X109631Y-227054D01*
X109240Y-226424D01*
X108535Y-226004D01*
X107595Y-225794D01*
X107046Y-225374D01*
X106811Y-224639D01*
X106968Y-223904D01*
X107360Y-223379D01*
X107908Y-223064D01*
X108456D01*
X109005Y-223274D01*
X109475Y-223799D01*
G01X113503Y-223064D02*
X115383D01*
G01X114443D02*
Y-229364D01*
G01X113503D02*
X115383D01*
G01X118785D02*
X120743Y-223064D01*
X122701Y-229364D01*
G01X121996Y-227159D02*
X119490D01*
G01X125241Y-229364D02*
Y-223064D01*
X128845Y-229364D01*
Y-223064D01*
G01X133813Y-226214D02*
X135380D01*
Y-228104D01*
X134910Y-228734D01*
X134361Y-229154D01*
X133578Y-229364D01*
X132795Y-229154D01*
X132246Y-228734D01*
X131776Y-228104D01*
X131463Y-227369D01*
X131306Y-226529D01*
Y-225794D01*
X131463Y-225164D01*
X131776Y-224429D01*
X132246Y-223799D01*
X132716Y-223379D01*
X133343Y-223064D01*
X133891D01*
X134518Y-223274D01*
X134988Y-223694D01*
G01X139486Y-230519D02*
X139800Y-229154D01*
G01X145943Y-223064D02*
Y-229364D01*
G01X144141Y-223064D02*
X147745D01*
G01X150285Y-229364D02*
X152243Y-223064D01*
X154201Y-229364D01*
G01X153496Y-227159D02*
X150990D01*
G01X158543Y-229364D02*
X157916Y-229259D01*
X157368Y-228839D01*
X156898Y-228209D01*
X156585Y-227474D01*
X156428Y-226634D01*
Y-225794D01*
X156585Y-224954D01*
X156898Y-224219D01*
X157368Y-223589D01*
X157916Y-223169D01*
X158543Y-223064D01*
X159170Y-223169D01*
X159718Y-223589D01*
X160188Y-224219D01*
X160501Y-224954D01*
X160658Y-225794D01*
Y-226634D01*
X160501Y-227474D01*
X160188Y-228209D01*
X159718Y-228839D01*
X159170Y-229259D01*
X158543Y-229364D01*
G01X171143D02*
Y-226529D01*
X169576Y-223064D01*
G01X172710D02*
X171143Y-226529D01*
G01X175720Y-223064D02*
Y-227579D01*
X176033Y-228524D01*
X176660Y-229154D01*
X177443Y-229364D01*
X178226Y-229154D01*
X178853Y-228524D01*
X179166Y-227579D01*
Y-223064D01*
G01X181785Y-229364D02*
X183743Y-223064D01*
X185701Y-229364D01*
G01X184996Y-227159D02*
X182490D01*
G01X188241Y-229364D02*
Y-223064D01*
X191845Y-229364D01*
Y-223064D01*
G01X37041Y-219364D02*
Y-213064D01*
X40645Y-219364D01*
Y-213064D01*
G01X45143Y-219364D02*
X44516Y-219259D01*
X43968Y-218839D01*
X43498Y-218209D01*
X43185Y-217474D01*
X43028Y-216634D01*
Y-215794D01*
X43185Y-214954D01*
X43498Y-214219D01*
X43968Y-213589D01*
X44516Y-213169D01*
X45143Y-213064D01*
X45770Y-213169D01*
X46318Y-213589D01*
X46788Y-214219D01*
X47101Y-214954D01*
X47258Y-215794D01*
Y-216634D01*
X47101Y-217474D01*
X46788Y-218209D01*
X46318Y-218839D01*
X45770Y-219259D01*
X45143Y-219364D01*
G01X51443Y-219574D02*
X51286Y-219469D01*
Y-219259D01*
X51443Y-219154D01*
X51600Y-219259D01*
Y-219469D01*
X51443Y-219574D01*
G01X57743Y-219364D02*
Y-213064D01*
X56803Y-214324D01*
G01Y-219364D02*
X58683D01*
G01X64043D02*
X64591Y-219259D01*
X65218Y-218944D01*
X65610Y-218419D01*
X65766Y-217684D01*
X65610Y-216949D01*
X65140Y-216319D01*
X64435Y-216004D01*
X63651D01*
X63181Y-215794D01*
X62790Y-215269D01*
X62633Y-214534D01*
X62868Y-213799D01*
X63416Y-213274D01*
X64043Y-213064D01*
X64670Y-213274D01*
X65218Y-213799D01*
X65453Y-214534D01*
X65296Y-215269D01*
X64905Y-215794D01*
X64435Y-216004D01*
X63651D01*
X62946Y-216319D01*
X62476Y-216949D01*
X62320Y-217684D01*
X62476Y-218419D01*
X62868Y-218944D01*
X63495Y-219259D01*
X64043Y-219364D01*
G01X70343D02*
X70891Y-219259D01*
X71518Y-218944D01*
X71910Y-218419D01*
X72066Y-217684D01*
X71910Y-216949D01*
X71440Y-216319D01*
X70735Y-216004D01*
X69951D01*
X69481Y-215794D01*
X69090Y-215269D01*
X68933Y-214534D01*
X69168Y-213799D01*
X69716Y-213274D01*
X70343Y-213064D01*
X70970Y-213274D01*
X71518Y-213799D01*
X71753Y-214534D01*
X71596Y-215269D01*
X71205Y-215794D01*
X70735Y-216004D01*
X69951D01*
X69246Y-216319D01*
X68776Y-216949D01*
X68620Y-217684D01*
X68776Y-218419D01*
X69168Y-218944D01*
X69795Y-219259D01*
X70343Y-219364D01*
G01X76486Y-220519D02*
X76800Y-219154D01*
G01X80593Y-213064D02*
X81690Y-219364D01*
X82943Y-213064D01*
X84196Y-219364D01*
X85293Y-213064D01*
G01X90810Y-219364D02*
X87676D01*
Y-213064D01*
X90810D01*
G01X89556Y-216109D02*
X87676D01*
G01X93741Y-219364D02*
Y-213064D01*
X97345Y-219364D01*
Y-213064D01*
G01X106498Y-219364D02*
Y-213064D01*
G01X109788D02*
Y-219364D01*
G01Y-216214D02*
X106498D01*
G01X112093Y-213064D02*
X113190Y-219364D01*
X114443Y-213064D01*
X115696Y-219364D01*
X116793Y-213064D01*
G01X118785Y-219364D02*
X120743Y-213064D01*
X122701Y-219364D01*
G01X121996Y-217159D02*
X119490D01*
G01X131855Y-214114D02*
X132325Y-213484D01*
X132873Y-213169D01*
X133500Y-213064D01*
X134283Y-213274D01*
X134831Y-213799D01*
X134988Y-214429D01*
X134910Y-215059D01*
X134596Y-215584D01*
X133030Y-216634D01*
X132325Y-217369D01*
X131855Y-218419D01*
X131698Y-219364D01*
X134988D01*
G01X137841D02*
Y-213064D01*
X141445Y-219364D01*
Y-213064D01*
G01X144220Y-219364D02*
Y-213064D01*
X145786D01*
X146413Y-213379D01*
X146883Y-213799D01*
X147275Y-214429D01*
X147588Y-215164D01*
X147666Y-216214D01*
X147588Y-217264D01*
X147275Y-217999D01*
X146883Y-218629D01*
X146413Y-219049D01*
X145786Y-219364D01*
X144220D01*
G01X156976D02*
Y-213064D01*
X158935D01*
X159561Y-213379D01*
X159953Y-213799D01*
X160110Y-214639D01*
X159953Y-215479D01*
X159483Y-216004D01*
X158935Y-216319D01*
X156976D01*
G01X158935D02*
X160110Y-219364D01*
G01X163120D02*
Y-213064D01*
X164686D01*
X165313Y-213379D01*
X165783Y-213799D01*
X166175Y-214429D01*
X166488Y-215164D01*
X166566Y-216214D01*
X166488Y-217264D01*
X166175Y-217999D01*
X165783Y-218629D01*
X165313Y-219049D01*
X164686Y-219364D01*
X163120D01*
G01X171143Y-219574D02*
X170986Y-219469D01*
Y-219259D01*
X171143Y-219154D01*
X171300Y-219259D01*
Y-219469D01*
X171143Y-219574D01*
G01X61143Y-206664D02*
X58623Y-206247D01*
X56418Y-204581D01*
X54528Y-202081D01*
X53268Y-199164D01*
X52638Y-195831D01*
Y-192497D01*
X53268Y-189164D01*
X54528Y-186247D01*
X56418Y-183748D01*
X58623Y-182081D01*
X61143Y-181664D01*
X63663Y-182081D01*
X65868Y-183748D01*
X67758Y-186247D01*
X69018Y-189164D01*
X69648Y-192497D01*
Y-195831D01*
X69018Y-199164D01*
X67758Y-202081D01*
X65868Y-204581D01*
X63663Y-206247D01*
X61143Y-206664D01*
G01X63663Y-199997D02*
X67443Y-206664D01*
G01X80988Y-189998D02*
Y-201664D01*
X82248Y-204581D01*
X84138Y-206247D01*
X86343Y-206664D01*
X88548Y-206247D01*
X90438Y-204581D01*
X91698Y-201664D01*
G01Y-206664D02*
Y-189998D01*
G01X117213Y-206664D02*
Y-189998D01*
G01Y-192914D02*
X115953Y-191248D01*
X114063Y-190414D01*
X111858Y-189998D01*
X109653Y-190831D01*
X107763Y-192497D01*
X106503Y-194998D01*
X105873Y-198331D01*
X106503Y-201664D01*
X107763Y-204165D01*
X109653Y-205831D01*
X111858Y-206664D01*
X114063Y-206247D01*
X115953Y-204998D01*
X117213Y-203331D01*
G01X131388Y-206664D02*
Y-189998D01*
G01Y-194164D02*
X132648Y-192081D01*
X134538Y-190414D01*
X137058Y-189998D01*
X139263Y-190414D01*
X141153Y-192081D01*
X142098Y-194998D01*
Y-206664D01*
G01X161943Y-181664D02*
Y-206664D01*
G01X157533Y-189998D02*
X166353D01*
G01X192813Y-206664D02*
Y-189998D01*
G01Y-192914D02*
X191553Y-191248D01*
X189663Y-190414D01*
X187458Y-189998D01*
X185253Y-190831D01*
X183363Y-192497D01*
X182103Y-194998D01*
X181473Y-198331D01*
X182103Y-201664D01*
X183363Y-204165D01*
X185253Y-205831D01*
X187458Y-206664D01*
X189663Y-206247D01*
X191553Y-204998D01*
X192813Y-203331D01*
G01X232493Y-186364D02*
Y-194364D01*
X236493D01*
G01X244293D02*
Y-189031D01*
G01Y-189964D02*
X243893Y-189431D01*
X243293Y-189164D01*
X242593Y-189031D01*
X241893Y-189297D01*
X241293Y-189831D01*
X240893Y-190631D01*
X240693Y-191697D01*
X240893Y-192764D01*
X241293Y-193564D01*
X241893Y-194097D01*
X242593Y-194364D01*
X243293Y-194231D01*
X243893Y-193831D01*
X244293Y-193298D01*
G01X248393Y-196764D02*
X248993Y-197031D01*
X249793Y-196764D01*
X250293Y-196231D01*
X250693Y-195564D01*
X251293Y-193431D01*
X252593Y-189031D01*
G01X249393D02*
X251293Y-193431D01*
G01X256993Y-190764D02*
X260193D01*
X259893Y-189831D01*
X259393Y-189297D01*
X258693Y-189031D01*
X257993Y-189164D01*
X257393Y-189564D01*
X256993Y-190497D01*
X256793Y-191298D01*
Y-192097D01*
X256993Y-192897D01*
X257493Y-193697D01*
X258093Y-194231D01*
X258793Y-194364D01*
X259493Y-194097D01*
X260193Y-193298D01*
G01X265093Y-194364D02*
Y-189031D01*
G01Y-190097D02*
X265593Y-189564D01*
X266093Y-189164D01*
X266793Y-189031D01*
X267293Y-189164D01*
X267893Y-189564D01*
G01X254793Y-236364D02*
X257193D01*
G01X255993D02*
Y-244364D01*
G01X254793D02*
X257193D01*
G01X262593D02*
Y-239031D01*
G01Y-240097D02*
X263093Y-239564D01*
X263593Y-239164D01*
X264293Y-239031D01*
X264793Y-239164D01*
X265393Y-239564D01*
G01X270493Y-240764D02*
X273693D01*
X273393Y-239831D01*
X272893Y-239297D01*
X272193Y-239031D01*
X271493Y-239164D01*
X270893Y-239564D01*
X270493Y-240497D01*
X270293Y-241298D01*
Y-242097D01*
X270493Y-242897D01*
X270993Y-243697D01*
X271593Y-244231D01*
X272293Y-244364D01*
X272993Y-244097D01*
X273693Y-243298D01*
G01X278293Y-244364D02*
Y-239031D01*
G01Y-240364D02*
X278693Y-239697D01*
X279293Y-239164D01*
X280093Y-239031D01*
X280793Y-239164D01*
X281393Y-239697D01*
X281693Y-240631D01*
Y-244364D01*
G01X286493Y-240764D02*
X289693D01*
X289393Y-239831D01*
X288893Y-239297D01*
X288193Y-239031D01*
X287493Y-239164D01*
X286893Y-239564D01*
X286493Y-240497D01*
X286293Y-241298D01*
Y-242097D01*
X286493Y-242897D01*
X286993Y-243697D01*
X287593Y-244231D01*
X288293Y-244364D01*
X288993Y-244097D01*
X289693Y-243298D01*
G01X243993Y-219364D02*
Y-211364D01*
X246393D01*
X247193Y-211764D01*
X247793Y-212697D01*
X247993Y-213764D01*
X247793Y-214831D01*
X247293Y-215631D01*
X246393Y-216031D01*
X243993D01*
G01X251493Y-219364D02*
X253993Y-211364D01*
X256493Y-219364D01*
G01X255593Y-216564D02*
X252393D01*
G01X259893Y-218298D02*
X260693Y-218964D01*
X261593Y-219364D01*
X262393D01*
X263193Y-218964D01*
X263793Y-218298D01*
X264093Y-217364D01*
X263893Y-216431D01*
X263393Y-215631D01*
X262493Y-215097D01*
X261293Y-214831D01*
X260593Y-214297D01*
X260293Y-213364D01*
X260493Y-212431D01*
X260993Y-211764D01*
X261693Y-211364D01*
X262393D01*
X263093Y-211631D01*
X263693Y-212297D01*
G01X269993Y-211364D02*
Y-219364D01*
G01X267693Y-211364D02*
X272293D01*
G01X276693Y-216697D02*
X279293D01*
G01X286793Y-215097D02*
X287193Y-214697D01*
X287493Y-214031D01*
X287693Y-213097D01*
X287493Y-212297D01*
X287093Y-211764D01*
X286393Y-211364D01*
X283693D01*
Y-219364D01*
X286993D01*
X287693Y-218831D01*
X288093Y-218031D01*
X288293Y-217097D01*
X288093Y-216164D01*
X287493Y-215364D01*
X286793Y-215097D01*
X283693D01*
G01X293993Y-219364D02*
X293193Y-219231D01*
X292493Y-218697D01*
X291893Y-217897D01*
X291493Y-216964D01*
X291293Y-215897D01*
Y-214831D01*
X291493Y-213764D01*
X291893Y-212831D01*
X292493Y-212031D01*
X293193Y-211497D01*
X293993Y-211364D01*
X294793Y-211497D01*
X295493Y-212031D01*
X296093Y-212831D01*
X296493Y-213764D01*
X296693Y-214831D01*
Y-215897D01*
X296493Y-216964D01*
X296093Y-217897D01*
X295493Y-218697D01*
X294793Y-219231D01*
X293993Y-219364D01*
G01X301993Y-211364D02*
Y-219364D01*
G01X299693Y-211364D02*
X304293D01*
G01X359093Y-237697D02*
X359693Y-236897D01*
X360393Y-236497D01*
X361193Y-236364D01*
X362193Y-236631D01*
X362893Y-237297D01*
X363093Y-238097D01*
X362993Y-238898D01*
X362593Y-239564D01*
X360593Y-240897D01*
X359693Y-241831D01*
X359093Y-243164D01*
X358893Y-244364D01*
X363093D01*
G01X368993Y-236364D02*
X368193Y-236631D01*
X367593Y-237297D01*
X367193Y-238097D01*
X366893Y-239164D01*
X366793Y-240364D01*
X366893Y-241564D01*
X367193Y-242631D01*
X367593Y-243431D01*
X368193Y-244097D01*
X368993Y-244364D01*
X369793Y-244097D01*
X370393Y-243431D01*
X370793Y-242631D01*
X371093Y-241564D01*
X371193Y-240364D01*
X371093Y-239164D01*
X370793Y-238097D01*
X370393Y-237297D01*
X369793Y-236631D01*
X368993Y-236364D01*
G01X376993Y-244364D02*
Y-236364D01*
X375793Y-237964D01*
G01Y-244364D02*
X378193D01*
G01X383093Y-237697D02*
X383693Y-236897D01*
X384393Y-236497D01*
X385193Y-236364D01*
X386193Y-236631D01*
X386893Y-237297D01*
X387093Y-238097D01*
X386993Y-238898D01*
X386593Y-239564D01*
X384593Y-240897D01*
X383693Y-241831D01*
X383093Y-243164D01*
X382893Y-244364D01*
X387093D01*
G01X391193Y-244631D02*
X394793Y-236364D01*
G01X400993Y-244364D02*
Y-236364D01*
X399793Y-237964D01*
G01Y-244364D02*
X402193D01*
G01X408993Y-236364D02*
X408193Y-236631D01*
X407593Y-237297D01*
X407193Y-238097D01*
X406893Y-239164D01*
X406793Y-240364D01*
X406893Y-241564D01*
X407193Y-242631D01*
X407593Y-243431D01*
X408193Y-244097D01*
X408993Y-244364D01*
X409793Y-244097D01*
X410393Y-243431D01*
X410793Y-242631D01*
X411093Y-241564D01*
X411193Y-240364D01*
X411093Y-239164D01*
X410793Y-238097D01*
X410393Y-237297D01*
X409793Y-236631D01*
X408993Y-236364D01*
G01X415193Y-244631D02*
X418793Y-236364D01*
G01X422793Y-242764D02*
X423393Y-243697D01*
X424193Y-244231D01*
X425093Y-244364D01*
X425893Y-244231D01*
X426693Y-243564D01*
X427193Y-242764D01*
X427293Y-241964D01*
X427093Y-241031D01*
X426393Y-240364D01*
X425693Y-240097D01*
X424793D01*
G01X425693D02*
X426293Y-239697D01*
X426793Y-239031D01*
X426993Y-238231D01*
X426793Y-237431D01*
X426293Y-236764D01*
X425393Y-236364D01*
X424493Y-236497D01*
X423593Y-237031D01*
G01X432993Y-244364D02*
Y-236364D01*
X431793Y-237964D01*
G01Y-244364D02*
X434193D01*
G01X358793Y-219364D02*
Y-211364D01*
X360793D01*
X361593Y-211764D01*
X362193Y-212297D01*
X362693Y-213097D01*
X363093Y-214031D01*
X363193Y-215364D01*
X363093Y-216697D01*
X362693Y-217631D01*
X362193Y-218431D01*
X361593Y-218964D01*
X360793Y-219364D01*
X358793D01*
G01X366493D02*
X368993Y-211364D01*
X371493Y-219364D01*
G01X370593Y-216564D02*
X367393D01*
G01X376993Y-211364D02*
Y-219364D01*
G01X374693Y-211364D02*
X379293D01*
G01X383093Y-216031D02*
X383793Y-215097D01*
X384393Y-214564D01*
X385193Y-214297D01*
X385893Y-214564D01*
X386393Y-215097D01*
X386793Y-215897D01*
X386893Y-216831D01*
X386793Y-217631D01*
X386393Y-218431D01*
X385793Y-219097D01*
X385093Y-219364D01*
X384293Y-219097D01*
X383593Y-218298D01*
X383193Y-217097D01*
X383093Y-215764D01*
X383293Y-214031D01*
X383593Y-213097D01*
X384093Y-212164D01*
X384793Y-211497D01*
X385493Y-211364D01*
X386193Y-211631D01*
X386693Y-212297D01*
G01X390393Y-219364D02*
Y-211364D01*
X392993Y-218031D01*
X395593Y-211364D01*
Y-219364D01*
G01X400993Y-211364D02*
Y-219364D01*
G01X398693Y-211364D02*
X403293D01*
G01X406893Y-219364D02*
Y-211364D01*
G01X411093D02*
Y-219364D01*
G01Y-215364D02*
X406893D01*
G01X414793Y-217764D02*
X415393Y-218697D01*
X416193Y-219231D01*
X417093Y-219364D01*
X417893Y-219231D01*
X418693Y-218564D01*
X419193Y-217764D01*
X419293Y-216964D01*
X419093Y-216031D01*
X418393Y-215364D01*
X417693Y-215097D01*
X416793D01*
G01X417693D02*
X418293Y-214697D01*
X418793Y-214031D01*
X418993Y-213231D01*
X418793Y-212431D01*
X418293Y-211764D01*
X417393Y-211364D01*
X416493Y-211497D01*
X415593Y-212031D01*
G01X422493Y-219364D02*
X424993Y-211364D01*
X427493Y-219364D01*
G01X426593Y-216564D02*
X423393D01*
G01X430793Y-219364D02*
Y-211364D01*
X432793D01*
X433593Y-211764D01*
X434193Y-212297D01*
X434693Y-213097D01*
X435093Y-214031D01*
X435193Y-215364D01*
X435093Y-216697D01*
X434693Y-217631D01*
X434193Y-218431D01*
X433593Y-218964D01*
X432793Y-219364D01*
X430793D01*
G01X440993Y-211364D02*
X440193Y-211631D01*
X439593Y-212297D01*
X439193Y-213097D01*
X438893Y-214164D01*
X438793Y-215364D01*
X438893Y-216564D01*
X439193Y-217631D01*
X439593Y-218431D01*
X440193Y-219097D01*
X440993Y-219364D01*
X441793Y-219097D01*
X442393Y-218431D01*
X442793Y-217631D01*
X443093Y-216564D01*
X443193Y-215364D01*
X443093Y-214164D01*
X442793Y-213097D01*
X442393Y-212297D01*
X441793Y-211631D01*
X440993Y-211364D01*
G01X380993Y-186364D02*
Y-194364D01*
G01X378693Y-186364D02*
X383293D01*
G01X387093Y-191031D02*
X387793Y-190097D01*
X388393Y-189564D01*
X389193Y-189297D01*
X389893Y-189564D01*
X390393Y-190097D01*
X390793Y-190897D01*
X390893Y-191831D01*
X390793Y-192631D01*
X390393Y-193431D01*
X389793Y-194097D01*
X389093Y-194364D01*
X388293Y-194097D01*
X387593Y-193298D01*
X387193Y-192097D01*
X387093Y-190764D01*
X387293Y-189031D01*
X387593Y-188097D01*
X388093Y-187164D01*
X388793Y-186497D01*
X389493Y-186364D01*
X390193Y-186631D01*
X390693Y-187297D01*
G01X394393Y-194364D02*
Y-186364D01*
X396993Y-193031D01*
X399593Y-186364D01*
Y-194364D01*
G01X401993Y-197031D02*
X407993D01*
G01X415193Y-187031D02*
X414593Y-186631D01*
X413893Y-186364D01*
X413093D01*
X412193Y-186764D01*
X411493Y-187431D01*
X410993Y-188231D01*
X410593Y-189564D01*
X410493Y-190764D01*
X410693Y-191964D01*
X410993Y-192764D01*
X411593Y-193564D01*
X412293Y-194097D01*
X412993Y-194364D01*
X413693D01*
X414393Y-194097D01*
X414993Y-193697D01*
X415493Y-193164D01*
G01X418393Y-194364D02*
Y-186364D01*
X420993Y-193031D01*
X423593Y-186364D01*
Y-194364D01*
G01X425993Y-197031D02*
X431993D01*
G01X434793Y-194364D02*
Y-186364D01*
X436793D01*
X437593Y-186764D01*
X438193Y-187297D01*
X438693Y-188097D01*
X439093Y-189031D01*
X439193Y-190364D01*
X439093Y-191697D01*
X438693Y-192631D01*
X438193Y-193431D01*
X437593Y-193964D01*
X436793Y-194364D01*
X434793D01*
G01X473793Y-244364D02*
Y-236364D01*
X475793D01*
X476593Y-236764D01*
X477193Y-237297D01*
X477693Y-238097D01*
X478093Y-239031D01*
X478193Y-240364D01*
X478093Y-241697D01*
X477693Y-242631D01*
X477193Y-243431D01*
X476593Y-243964D01*
X475793Y-244364D01*
X473793D01*
G01X503493D02*
Y-236364D01*
X502293Y-237964D01*
G01Y-244364D02*
X504693D01*
G01X509593Y-241031D02*
X510293Y-240097D01*
X510893Y-239564D01*
X511693Y-239297D01*
X512393Y-239564D01*
X512893Y-240097D01*
X513293Y-240897D01*
X513393Y-241831D01*
X513293Y-242631D01*
X512893Y-243431D01*
X512293Y-244097D01*
X511593Y-244364D01*
X510793Y-244097D01*
X510093Y-243298D01*
X509693Y-242097D01*
X509593Y-240764D01*
X509793Y-239031D01*
X510093Y-238097D01*
X510593Y-237164D01*
X511293Y-236497D01*
X511993Y-236364D01*
X512693Y-236631D01*
X513193Y-237297D01*
G54D19*
X45554Y488557D03*
X57154D03*
X116984Y461818D03*
X105384D03*
X195789Y450513D03*
X184189D03*
X295177Y595628D03*
X306777D03*
X387677Y591821D03*
X399277D03*
G54D28*
X156251Y297210D03*
Y303010D03*
X166297Y297499D03*
Y303299D03*
X208947Y343717D03*
Y349517D03*
X203509Y481453D03*
Y487253D03*
X220218Y266687D03*
Y272487D03*
X214447Y343717D03*
Y349517D03*
X218709Y498253D03*
Y492453D03*
X225034Y541049D03*
Y546849D03*
X244201Y326196D03*
Y320396D03*
X251717Y335325D03*
Y341125D03*
X250109Y572109D03*
Y577909D03*
X279004Y494955D03*
Y489155D03*
X291199Y494792D03*
Y488992D03*
X284724Y495518D03*
Y489718D03*
X306221Y79539D03*
Y85339D03*
X300821Y79539D03*
Y85339D03*
X296735Y487826D03*
Y493626D03*
X435451Y251925D03*
Y257725D03*
X494065Y486325D03*
Y492125D03*
X508438Y484300D03*
Y490100D03*
X683230Y454899D03*
Y460699D03*
X689126Y454965D03*
X694833Y464340D03*
Y470140D03*
X689126Y460765D03*
X695082Y480906D03*
Y486706D03*
G54D37*
X396411Y664578D03*
Y669696D03*
X403989Y664578D03*
Y667137D03*
Y669696D03*
X523611Y218900D03*
Y216341D03*
Y221459D03*
X531189Y216341D03*
Y221459D03*
G54D46*
X590999Y69167D03*
Y77041D03*
Y84915D03*
X615657Y69167D03*
Y77041D03*
Y84915D03*
G54D38*
X456963Y479623D03*
X465293D03*
X456963Y491223D03*
X465293D03*
G54D29*
X161109Y564853D03*
X155309D03*
X203012Y492651D03*
X208812D03*
X227734Y486164D03*
X221934D03*
X254413Y117582D03*
X260213D03*
X271977Y546643D03*
X277777D03*
X323957Y117410D03*
X329757D03*
X424400Y541007D03*
X430200D03*
X492380Y594236D03*
X507902Y455990D03*
X504538Y556925D03*
X510338D03*
Y562425D03*
X504538D03*
X498180Y594236D03*
X513702Y455990D03*
X542879Y411620D03*
X548679D03*
X683395Y468030D03*
X677595D03*
X679461Y485834D03*
X673661D03*
X679461Y480334D03*
X673661D03*
X679461Y474834D03*
X673661D03*
X697759Y475492D03*
X686720Y475042D03*
X692520D03*
X706395Y468130D03*
X712195D03*
X706395Y462530D03*
X712195D03*
X703559Y475492D03*
G54D47*
X590999Y92789D03*
X615657D03*
G54D39*
X504941Y213711D03*
X507500D03*
X510059D03*
X504941Y221289D03*
X510059D03*
G54D48*
X605796Y165160D03*
X609733Y215672D03*
G54D49*
X605796Y174845D03*
M02*
